G04 ================== begin FILE IDENTIFICATION RECORD ==================*
G04 Layout Name:  12523-1.brd*
G04 Film Name:    NOTICE*
G04 File Format:  Gerber RS274X*
G04 File Origin:  Cadence Allegro 16.2-s031*
G04 Origin Date:  Fri Oct 19 14:59:11 2012*
G04 *
G04 Layer:  MANUFACTURING/THERMAL*
G04 *
G04 Offset:    (0.00 0.00)*
G04 Mirror:    No*
G04 Mode:      Positive*
G04 Rotation:  0*
G04 FullContactRelief:  No*
G04 UndefLineWidth:     6.00*
G04 ================== end FILE IDENTIFICATION RECORD ====================*
%FSLAX35Y35*MOIN*%
%IR0*IPPOS*OFA0.00000B0.00000*MIA0B0*SFA1.00000B1.00000*%
%ADD10C,.02*%
%ADD11C,.015*%
%ADD12C,.006*%
G75*
%LPD*%
G75*
G36*
G01X58318Y-52018D02*
G02X36772Y-30472I7501J29047D01*
G01X31632Y-30471D01*
G03X58319Y-57158I34187J7500D01*
G01X58318Y-52018D01*
G37*
G36*
G01X36772Y-15471D02*
G02X58318Y6076I29047J-7500D01*
G01X58319Y11216D01*
G03X31632Y-15472I7500J-34187D01*
G01X36772Y-15471D01*
G37*
G36*
G01X113189Y-502090D02*
G02X85630Y-464533I11812J37557D01*
G01Y-448785D01*
X91535D01*
Y-464533D01*
G03X113189Y-495844I33464J0D01*
G01Y-502090D01*
G37*
G36*
G01X85630Y-409415D02*
Y-393667D01*
G02X113189Y-356110I39371J0D01*
G01Y-362356D01*
G03X91535Y-393667I11810J-31311D01*
G01Y-409415D01*
X85630D01*
G37*
G36*
G01X94866Y-30472D02*
G02X73319Y-52018I-29047J7501D01*
G01X73318Y-57158D01*
G03X100006Y-30471I-7499J34187D01*
G01X94866Y-30472D01*
G37*
G36*
G01X73319Y6076D02*
G02X94866Y-15471I-7500J-29047D01*
G01X100006Y-15472D01*
G03X73318Y11216I-34187J-7499D01*
G01X73319Y6076D01*
G37*
G36*
G01X136811Y-502090D02*
Y-495844D01*
G03X158465Y-464533I-11810J31311D01*
G01Y-448785D01*
X164370D01*
Y-464533D01*
G02X136811Y-502090I-39371J0D01*
G37*
G36*
G01X158465Y-409415D02*
Y-393667D01*
G03X136811Y-362356I-33464J0D01*
G01Y-356110D01*
G02X164370Y-393667I-11812J-37557D01*
G01Y-409415D01*
X158465D01*
G37*
G54D10*
G01X-109408Y-660900D02*
Y-648400D01*
X-101492D01*
G01X-104408Y-654442D02*
X-109408D01*
G01X-89950Y-660900D02*
X-91200Y-660692D01*
X-92450Y-659859D01*
X-93284Y-658400D01*
X-93700Y-656733D01*
X-93284Y-655067D01*
X-92450Y-653608D01*
X-91200Y-652775D01*
X-89950Y-652567D01*
X-88700Y-652775D01*
X-87450Y-653608D01*
X-86617Y-655067D01*
X-86408Y-656733D01*
X-86617Y-658400D01*
X-87450Y-659859D01*
X-88700Y-660692D01*
X-89950Y-660900D01*
G01X-77367D02*
Y-652567D01*
G01Y-654233D02*
X-76325Y-653400D01*
X-75283Y-652775D01*
X-73825Y-652567D01*
X-72783Y-652775D01*
X-71533Y-653400D01*
G01X-47408Y-650483D02*
X-46158Y-649234D01*
X-44700Y-648608D01*
X-43033Y-648400D01*
X-40950Y-648817D01*
X-39492Y-649858D01*
X-39075Y-651108D01*
X-39283Y-652359D01*
X-40117Y-653400D01*
X-44283Y-655483D01*
X-46158Y-656942D01*
X-47408Y-659025D01*
X-47825Y-660900D01*
X-39075D01*
G01X-28367D02*
X-27950Y-658192D01*
X-27325Y-655900D01*
X-26492Y-653817D01*
X-25450Y-651525D01*
X-23783Y-648400D01*
X-32117D01*
G01X-9950Y-660900D02*
Y-648400D01*
X-17659Y-657358D01*
X-7241D01*
G01X-1325Y-660900D02*
X7425Y-648400D01*
G01X-1325D02*
X7425Y-660900D01*
G01X31133Y-664025D02*
X32592Y-664858D01*
X34258Y-665067D01*
X35717Y-664858D01*
X36967Y-663817D01*
X37800Y-662358D01*
Y-652567D01*
G01Y-654233D02*
X36967Y-653400D01*
X35717Y-652775D01*
X34258Y-652567D01*
X32592Y-652983D01*
X31550Y-653817D01*
X30716Y-655275D01*
X30300Y-656733D01*
X30508Y-657984D01*
X31342Y-659442D01*
X32592Y-660483D01*
X34258Y-660900D01*
X35508Y-660692D01*
X36967Y-659859D01*
X37800Y-659025D01*
G01X46425Y-655275D02*
X53092D01*
X52467Y-653817D01*
X51425Y-652983D01*
X49967Y-652567D01*
X48508Y-652775D01*
X47258Y-653400D01*
X46425Y-654858D01*
X46008Y-656109D01*
Y-657358D01*
X46425Y-658608D01*
X47467Y-659859D01*
X48717Y-660692D01*
X50175Y-660900D01*
X51633Y-660483D01*
X53092Y-659234D01*
G01X62133Y-660900D02*
Y-652567D01*
G01Y-654233D02*
X63175Y-653400D01*
X64217Y-652775D01*
X65675Y-652567D01*
X66717Y-652775D01*
X67967Y-653400D01*
G01X76800Y-660900D02*
Y-648400D01*
G01Y-654650D02*
X77842Y-653400D01*
X79092Y-652775D01*
X80342Y-652567D01*
X82217Y-652983D01*
X83467Y-653817D01*
X84300Y-655275D01*
Y-656942D01*
X83883Y-658608D01*
X83050Y-659859D01*
X81592Y-660692D01*
X80342Y-660900D01*
X79092Y-660692D01*
X77842Y-660067D01*
X76800Y-659025D01*
G01X92925Y-655275D02*
X99592D01*
X98967Y-653817D01*
X97925Y-652983D01*
X96467Y-652567D01*
X95008Y-652775D01*
X93758Y-653400D01*
X92925Y-654858D01*
X92508Y-656109D01*
Y-657358D01*
X92925Y-658608D01*
X93967Y-659859D01*
X95217Y-660692D01*
X96675Y-660900D01*
X98133Y-660483D01*
X99592Y-659234D01*
G01X108633Y-660900D02*
Y-652567D01*
G01Y-654233D02*
X109675Y-653400D01*
X110717Y-652775D01*
X112175Y-652567D01*
X113217Y-652775D01*
X114467Y-653400D01*
G01X141300Y-660900D02*
Y-650275D01*
X141717Y-649234D01*
X142550Y-648608D01*
X143800Y-648400D01*
X145050Y-648817D01*
X145675Y-649858D01*
G01X143175Y-653400D02*
X139008D01*
G01X158050Y-660900D02*
X156800Y-660692D01*
X155550Y-659859D01*
X154716Y-658400D01*
X154300Y-656733D01*
X154716Y-655067D01*
X155550Y-653608D01*
X156800Y-652775D01*
X158050Y-652567D01*
X159300Y-652775D01*
X160550Y-653608D01*
X161383Y-655067D01*
X161592Y-656733D01*
X161383Y-658400D01*
X160550Y-659859D01*
X159300Y-660692D01*
X158050Y-660900D01*
G01X170633D02*
Y-652567D01*
G01Y-654233D02*
X171675Y-653400D01*
X172717Y-652775D01*
X174175Y-652567D01*
X175217Y-652775D01*
X176467Y-653400D01*
G01X182800Y-660900D02*
Y-652567D01*
G01Y-654858D02*
X183425Y-653817D01*
X184467Y-652983D01*
X185925Y-652567D01*
X187383Y-652983D01*
X188425Y-653817D01*
X189050Y-654858D01*
Y-660900D01*
G01Y-654858D02*
X189675Y-653817D01*
X190717Y-652983D01*
X192175Y-652567D01*
X193633Y-652983D01*
X194675Y-653817D01*
X195300Y-655067D01*
Y-660900D01*
G01X208300D02*
Y-652567D01*
G01Y-654025D02*
X207467Y-653192D01*
X206217Y-652775D01*
X204758Y-652567D01*
X203300Y-652983D01*
X202050Y-653817D01*
X201216Y-655067D01*
X200800Y-656733D01*
X201216Y-658400D01*
X202050Y-659650D01*
X203300Y-660483D01*
X204758Y-660900D01*
X206217Y-660692D01*
X207467Y-660067D01*
X208300Y-659234D01*
G01X220050Y-648400D02*
Y-660900D01*
G01X217133Y-652567D02*
X222967D01*
G01X251050Y-648400D02*
Y-660900D01*
G01X248133Y-652567D02*
X253967D01*
G01X263008Y-660900D02*
Y-648400D01*
G01Y-654442D02*
X264050Y-653400D01*
X265092Y-652775D01*
X266758Y-652567D01*
X268008Y-652775D01*
X269467Y-653608D01*
X270092Y-654858D01*
Y-660900D01*
G01X278925Y-655275D02*
X285592D01*
X284967Y-653817D01*
X283925Y-652983D01*
X282467Y-652567D01*
X281008Y-652775D01*
X279758Y-653400D01*
X278925Y-654858D01*
X278508Y-656109D01*
Y-657358D01*
X278925Y-658608D01*
X279967Y-659859D01*
X281217Y-660692D01*
X282675Y-660900D01*
X284133Y-660483D01*
X285592Y-659234D01*
G01X294633Y-660900D02*
Y-652567D01*
G01Y-654233D02*
X295675Y-653400D01*
X296717Y-652775D01*
X298175Y-652567D01*
X299217Y-652775D01*
X300467Y-653400D01*
G01X306800Y-660900D02*
Y-652567D01*
G01Y-654858D02*
X307425Y-653817D01*
X308467Y-652983D01*
X309925Y-652567D01*
X311383Y-652983D01*
X312425Y-653817D01*
X313050Y-654858D01*
Y-660900D01*
G01Y-654858D02*
X313675Y-653817D01*
X314717Y-652983D01*
X316175Y-652567D01*
X317633Y-652983D01*
X318675Y-653817D01*
X319300Y-655067D01*
Y-660900D01*
G01X332300D02*
Y-652567D01*
G01Y-654025D02*
X331467Y-653192D01*
X330217Y-652775D01*
X328758Y-652567D01*
X327300Y-652983D01*
X326050Y-653817D01*
X325216Y-655067D01*
X324800Y-656733D01*
X325216Y-658400D01*
X326050Y-659650D01*
X327300Y-660483D01*
X328758Y-660900D01*
X330217Y-660692D01*
X331467Y-660067D01*
X332300Y-659234D01*
G01X344050Y-660900D02*
Y-648400D01*
G01X372133Y-660900D02*
Y-652567D01*
G01Y-654233D02*
X373175Y-653400D01*
X374217Y-652775D01*
X375675Y-652567D01*
X376717Y-652775D01*
X377967Y-653400D01*
G01X387425Y-655275D02*
X394092D01*
X393467Y-653817D01*
X392425Y-652983D01*
X390967Y-652567D01*
X389508Y-652775D01*
X388258Y-653400D01*
X387425Y-654858D01*
X387008Y-656109D01*
Y-657358D01*
X387425Y-658608D01*
X388467Y-659859D01*
X389717Y-660692D01*
X391175Y-660900D01*
X392633Y-660483D01*
X394092Y-659234D01*
G01X406050Y-660900D02*
Y-648400D01*
G01X421550Y-652567D02*
Y-660900D01*
G01Y-649234D02*
X421133Y-649025D01*
Y-648608D01*
X421550Y-648400D01*
X421967Y-648608D01*
Y-649025D01*
X421550Y-649234D01*
G01X433925Y-655275D02*
X440592D01*
X439967Y-653817D01*
X438925Y-652983D01*
X437467Y-652567D01*
X436008Y-652775D01*
X434758Y-653400D01*
X433925Y-654858D01*
X433508Y-656109D01*
Y-657358D01*
X433925Y-658608D01*
X434967Y-659859D01*
X436217Y-660692D01*
X437675Y-660900D01*
X439133Y-660483D01*
X440592Y-659234D01*
G01X451300Y-660900D02*
Y-650275D01*
X451717Y-649234D01*
X452550Y-648608D01*
X453800Y-648400D01*
X455050Y-648817D01*
X455675Y-649858D01*
G01X453175Y-653400D02*
X449008D01*
G01X-106700Y-682600D02*
Y-671975D01*
X-106283Y-670934D01*
X-105450Y-670308D01*
X-104200Y-670100D01*
X-102950Y-670517D01*
X-102325Y-671558D01*
G01X-104825Y-675100D02*
X-108992D01*
G01X-89950Y-682600D02*
X-91200Y-682392D01*
X-92450Y-681559D01*
X-93284Y-680100D01*
X-93700Y-678433D01*
X-93284Y-676767D01*
X-92450Y-675308D01*
X-91200Y-674475D01*
X-89950Y-674267D01*
X-88700Y-674475D01*
X-87450Y-675308D01*
X-86617Y-676767D01*
X-86408Y-678433D01*
X-86617Y-680100D01*
X-87450Y-681559D01*
X-88700Y-682392D01*
X-89950Y-682600D01*
G01X-74450D02*
Y-670100D01*
G01X-58950Y-682600D02*
Y-670100D01*
G01X-43450Y-682600D02*
X-44700Y-682392D01*
X-45950Y-681559D01*
X-46784Y-680100D01*
X-47200Y-678433D01*
X-46784Y-676767D01*
X-45950Y-675308D01*
X-44700Y-674475D01*
X-43450Y-674267D01*
X-42200Y-674475D01*
X-40950Y-675308D01*
X-40117Y-676767D01*
X-39908Y-678433D01*
X-40117Y-680100D01*
X-40950Y-681559D01*
X-42200Y-682392D01*
X-43450Y-682600D01*
G01X-33159Y-674267D02*
X-30658Y-682600D01*
X-27950Y-674267D01*
X-25242Y-682600D01*
X-22741Y-674267D01*
G01X133Y-685725D02*
X1592Y-686558D01*
X3258Y-686767D01*
X4717Y-686558D01*
X5967Y-685517D01*
X6800Y-684058D01*
Y-674267D01*
G01Y-675933D02*
X5967Y-675100D01*
X4717Y-674475D01*
X3258Y-674267D01*
X1592Y-674683D01*
X550Y-675517D01*
X-284Y-676975D01*
X-700Y-678433D01*
X-492Y-679684D01*
X342Y-681142D01*
X1592Y-682183D01*
X3258Y-682600D01*
X4508Y-682392D01*
X5967Y-681559D01*
X6800Y-680725D01*
G01X15425Y-676975D02*
X22092D01*
X21467Y-675517D01*
X20425Y-674683D01*
X18967Y-674267D01*
X17508Y-674475D01*
X16258Y-675100D01*
X15425Y-676558D01*
X15008Y-677809D01*
Y-679058D01*
X15425Y-680308D01*
X16467Y-681559D01*
X17717Y-682392D01*
X19175Y-682600D01*
X20633Y-682183D01*
X22092Y-680934D01*
G01X31133Y-682600D02*
Y-674267D01*
G01Y-675933D02*
X32175Y-675100D01*
X33217Y-674475D01*
X34675Y-674267D01*
X35717Y-674475D01*
X36967Y-675100D01*
G01X45800Y-682600D02*
Y-670100D01*
G01Y-676350D02*
X46842Y-675100D01*
X48092Y-674475D01*
X49342Y-674267D01*
X51217Y-674683D01*
X52467Y-675517D01*
X53300Y-676975D01*
Y-678642D01*
X52883Y-680308D01*
X52050Y-681559D01*
X50592Y-682392D01*
X49342Y-682600D01*
X48092Y-682392D01*
X46842Y-681767D01*
X45800Y-680725D01*
G01X61925Y-676975D02*
X68592D01*
X67967Y-675517D01*
X66925Y-674683D01*
X65467Y-674267D01*
X64008Y-674475D01*
X62758Y-675100D01*
X61925Y-676558D01*
X61508Y-677809D01*
Y-679058D01*
X61925Y-680308D01*
X62967Y-681559D01*
X64217Y-682392D01*
X65675Y-682600D01*
X67133Y-682183D01*
X68592Y-680934D01*
G01X77633Y-682600D02*
Y-674267D01*
G01Y-675933D02*
X78675Y-675100D01*
X79717Y-674475D01*
X81175Y-674267D01*
X82217Y-674475D01*
X83467Y-675100D01*
G01X115300Y-670100D02*
Y-682600D01*
G01Y-680725D02*
X114467Y-681767D01*
X113217Y-682392D01*
X111758Y-682600D01*
X110092Y-682183D01*
X108842Y-681142D01*
X108008Y-679892D01*
X107800Y-678433D01*
X108008Y-676975D01*
X108842Y-675725D01*
X110092Y-674683D01*
X111758Y-674267D01*
X113217Y-674475D01*
X114258Y-674892D01*
X115300Y-675725D01*
G01X123925Y-676975D02*
X130592D01*
X129967Y-675517D01*
X128925Y-674683D01*
X127467Y-674267D01*
X126008Y-674475D01*
X124758Y-675100D01*
X123925Y-676558D01*
X123508Y-677809D01*
Y-679058D01*
X123925Y-680308D01*
X124967Y-681559D01*
X126217Y-682392D01*
X127675Y-682600D01*
X129133Y-682183D01*
X130592Y-680934D01*
G01X139425Y-681142D02*
X140467Y-681975D01*
X141925Y-682600D01*
X143175D01*
X144425Y-682183D01*
X145258Y-681559D01*
X145675Y-680725D01*
X145467Y-679475D01*
X144633Y-678850D01*
X140883Y-677600D01*
X140050Y-676142D01*
X140467Y-675100D01*
X141300Y-674475D01*
X142550Y-674267D01*
X143800Y-674475D01*
X145050Y-675100D01*
G01X158050Y-674267D02*
Y-682600D01*
G01Y-670934D02*
X157633Y-670725D01*
Y-670308D01*
X158050Y-670100D01*
X158467Y-670308D01*
Y-670725D01*
X158050Y-670934D01*
G01X170633Y-685725D02*
X172092Y-686558D01*
X173758Y-686767D01*
X175217Y-686558D01*
X176467Y-685517D01*
X177300Y-684058D01*
Y-674267D01*
G01Y-675933D02*
X176467Y-675100D01*
X175217Y-674475D01*
X173758Y-674267D01*
X172092Y-674683D01*
X171050Y-675517D01*
X170216Y-676975D01*
X169800Y-678433D01*
X170008Y-679684D01*
X170842Y-681142D01*
X172092Y-682183D01*
X173758Y-682600D01*
X175008Y-682392D01*
X176467Y-681559D01*
X177300Y-680725D01*
G01X185508Y-682600D02*
Y-674267D01*
G01Y-676350D02*
X186342Y-675308D01*
X187592Y-674475D01*
X189258Y-674267D01*
X190717Y-674475D01*
X191967Y-675308D01*
X192592Y-676767D01*
Y-682600D01*
G01X-99808Y-207000D02*
Y-194500D01*
X-91892D01*
G01X-94808Y-200542D02*
X-99808D01*
G01X-80350Y-207000D02*
X-81600Y-206792D01*
X-82850Y-205959D01*
X-83684Y-204500D01*
X-84100Y-202833D01*
X-83684Y-201167D01*
X-82850Y-199708D01*
X-81600Y-198875D01*
X-80350Y-198667D01*
X-79100Y-198875D01*
X-77850Y-199708D01*
X-77017Y-201167D01*
X-76808Y-202833D01*
X-77017Y-204500D01*
X-77850Y-205959D01*
X-79100Y-206792D01*
X-80350Y-207000D01*
G01X-67767D02*
Y-198667D01*
G01Y-200333D02*
X-66725Y-199500D01*
X-65683Y-198875D01*
X-64225Y-198667D01*
X-63183Y-198875D01*
X-61933Y-199500D01*
G01X-37808Y-196583D02*
X-36558Y-195334D01*
X-35100Y-194708D01*
X-33433Y-194500D01*
X-31350Y-194917D01*
X-29892Y-195958D01*
X-29475Y-197208D01*
X-29683Y-198459D01*
X-30517Y-199500D01*
X-34683Y-201583D01*
X-36558Y-203042D01*
X-37808Y-205125D01*
X-38225Y-207000D01*
X-29475D01*
G01X-18767D02*
X-18350Y-204292D01*
X-17725Y-202000D01*
X-16892Y-199917D01*
X-15850Y-197625D01*
X-14183Y-194500D01*
X-22517D01*
G01X-350Y-207000D02*
Y-194500D01*
X-8059Y-203458D01*
X2359D01*
G01X8275Y-207000D02*
X17025Y-194500D01*
G01X8275D02*
X17025Y-207000D01*
G01X40733Y-210125D02*
X42192Y-210958D01*
X43858Y-211167D01*
X45317Y-210958D01*
X46567Y-209917D01*
X47400Y-208458D01*
Y-198667D01*
G01Y-200333D02*
X46567Y-199500D01*
X45317Y-198875D01*
X43858Y-198667D01*
X42192Y-199083D01*
X41150Y-199917D01*
X40316Y-201375D01*
X39900Y-202833D01*
X40108Y-204084D01*
X40942Y-205542D01*
X42192Y-206583D01*
X43858Y-207000D01*
X45108Y-206792D01*
X46567Y-205959D01*
X47400Y-205125D01*
G01X56025Y-201375D02*
X62692D01*
X62067Y-199917D01*
X61025Y-199083D01*
X59567Y-198667D01*
X58108Y-198875D01*
X56858Y-199500D01*
X56025Y-200958D01*
X55608Y-202209D01*
Y-203458D01*
X56025Y-204708D01*
X57067Y-205959D01*
X58317Y-206792D01*
X59775Y-207000D01*
X61233Y-206583D01*
X62692Y-205334D01*
G01X71733Y-207000D02*
Y-198667D01*
G01Y-200333D02*
X72775Y-199500D01*
X73817Y-198875D01*
X75275Y-198667D01*
X76317Y-198875D01*
X77567Y-199500D01*
G01X86400Y-207000D02*
Y-194500D01*
G01Y-200750D02*
X87442Y-199500D01*
X88692Y-198875D01*
X89942Y-198667D01*
X91817Y-199083D01*
X93067Y-199917D01*
X93900Y-201375D01*
Y-203042D01*
X93483Y-204708D01*
X92650Y-205959D01*
X91192Y-206792D01*
X89942Y-207000D01*
X88692Y-206792D01*
X87442Y-206167D01*
X86400Y-205125D01*
G01X102525Y-201375D02*
X109192D01*
X108567Y-199917D01*
X107525Y-199083D01*
X106067Y-198667D01*
X104608Y-198875D01*
X103358Y-199500D01*
X102525Y-200958D01*
X102108Y-202209D01*
Y-203458D01*
X102525Y-204708D01*
X103567Y-205959D01*
X104817Y-206792D01*
X106275Y-207000D01*
X107733Y-206583D01*
X109192Y-205334D01*
G01X118233Y-207000D02*
Y-198667D01*
G01Y-200333D02*
X119275Y-199500D01*
X120317Y-198875D01*
X121775Y-198667D01*
X122817Y-198875D01*
X124067Y-199500D01*
G01X150900Y-207000D02*
Y-196375D01*
X151317Y-195334D01*
X152150Y-194708D01*
X153400Y-194500D01*
X154650Y-194917D01*
X155275Y-195958D01*
G01X152775Y-199500D02*
X148608D01*
G01X167650Y-207000D02*
X166400Y-206792D01*
X165150Y-205959D01*
X164316Y-204500D01*
X163900Y-202833D01*
X164316Y-201167D01*
X165150Y-199708D01*
X166400Y-198875D01*
X167650Y-198667D01*
X168900Y-198875D01*
X170150Y-199708D01*
X170983Y-201167D01*
X171192Y-202833D01*
X170983Y-204500D01*
X170150Y-205959D01*
X168900Y-206792D01*
X167650Y-207000D01*
G01X180233D02*
Y-198667D01*
G01Y-200333D02*
X181275Y-199500D01*
X182317Y-198875D01*
X183775Y-198667D01*
X184817Y-198875D01*
X186067Y-199500D01*
G01X192400Y-207000D02*
Y-198667D01*
G01Y-200958D02*
X193025Y-199917D01*
X194067Y-199083D01*
X195525Y-198667D01*
X196983Y-199083D01*
X198025Y-199917D01*
X198650Y-200958D01*
Y-207000D01*
G01Y-200958D02*
X199275Y-199917D01*
X200317Y-199083D01*
X201775Y-198667D01*
X203233Y-199083D01*
X204275Y-199917D01*
X204900Y-201167D01*
Y-207000D01*
G01X217900D02*
Y-198667D01*
G01Y-200125D02*
X217067Y-199292D01*
X215817Y-198875D01*
X214358Y-198667D01*
X212900Y-199083D01*
X211650Y-199917D01*
X210816Y-201167D01*
X210400Y-202833D01*
X210816Y-204500D01*
X211650Y-205750D01*
X212900Y-206583D01*
X214358Y-207000D01*
X215817Y-206792D01*
X217067Y-206167D01*
X217900Y-205334D01*
G01X229650Y-194500D02*
Y-207000D01*
G01X226733Y-198667D02*
X232567D01*
G01X260650Y-194500D02*
Y-207000D01*
G01X257733Y-198667D02*
X263567D01*
G01X272608Y-207000D02*
Y-194500D01*
G01Y-200542D02*
X273650Y-199500D01*
X274692Y-198875D01*
X276358Y-198667D01*
X277608Y-198875D01*
X279067Y-199708D01*
X279692Y-200958D01*
Y-207000D01*
G01X288525Y-201375D02*
X295192D01*
X294567Y-199917D01*
X293525Y-199083D01*
X292067Y-198667D01*
X290608Y-198875D01*
X289358Y-199500D01*
X288525Y-200958D01*
X288108Y-202209D01*
Y-203458D01*
X288525Y-204708D01*
X289567Y-205959D01*
X290817Y-206792D01*
X292275Y-207000D01*
X293733Y-206583D01*
X295192Y-205334D01*
G01X304233Y-207000D02*
Y-198667D01*
G01Y-200333D02*
X305275Y-199500D01*
X306317Y-198875D01*
X307775Y-198667D01*
X308817Y-198875D01*
X310067Y-199500D01*
G01X316400Y-207000D02*
Y-198667D01*
G01Y-200958D02*
X317025Y-199917D01*
X318067Y-199083D01*
X319525Y-198667D01*
X320983Y-199083D01*
X322025Y-199917D01*
X322650Y-200958D01*
Y-207000D01*
G01Y-200958D02*
X323275Y-199917D01*
X324317Y-199083D01*
X325775Y-198667D01*
X327233Y-199083D01*
X328275Y-199917D01*
X328900Y-201167D01*
Y-207000D01*
G01X341900D02*
Y-198667D01*
G01Y-200125D02*
X341067Y-199292D01*
X339817Y-198875D01*
X338358Y-198667D01*
X336900Y-199083D01*
X335650Y-199917D01*
X334816Y-201167D01*
X334400Y-202833D01*
X334816Y-204500D01*
X335650Y-205750D01*
X336900Y-206583D01*
X338358Y-207000D01*
X339817Y-206792D01*
X341067Y-206167D01*
X341900Y-205334D01*
G01X353650Y-207000D02*
Y-194500D01*
G01X381733Y-207000D02*
Y-198667D01*
G01Y-200333D02*
X382775Y-199500D01*
X383817Y-198875D01*
X385275Y-198667D01*
X386317Y-198875D01*
X387567Y-199500D01*
G01X397025Y-201375D02*
X403692D01*
X403067Y-199917D01*
X402025Y-199083D01*
X400567Y-198667D01*
X399108Y-198875D01*
X397858Y-199500D01*
X397025Y-200958D01*
X396608Y-202209D01*
Y-203458D01*
X397025Y-204708D01*
X398067Y-205959D01*
X399317Y-206792D01*
X400775Y-207000D01*
X402233Y-206583D01*
X403692Y-205334D01*
G01X415650Y-207000D02*
Y-194500D01*
G01X431150Y-198667D02*
Y-207000D01*
G01Y-195334D02*
X430733Y-195125D01*
Y-194708D01*
X431150Y-194500D01*
X431567Y-194708D01*
Y-195125D01*
X431150Y-195334D01*
G01X443525Y-201375D02*
X450192D01*
X449567Y-199917D01*
X448525Y-199083D01*
X447067Y-198667D01*
X445608Y-198875D01*
X444358Y-199500D01*
X443525Y-200958D01*
X443108Y-202209D01*
Y-203458D01*
X443525Y-204708D01*
X444567Y-205959D01*
X445817Y-206792D01*
X447275Y-207000D01*
X448733Y-206583D01*
X450192Y-205334D01*
G01X460900Y-207000D02*
Y-196375D01*
X461317Y-195334D01*
X462150Y-194708D01*
X463400Y-194500D01*
X464650Y-194917D01*
X465275Y-195958D01*
G01X462775Y-199500D02*
X458608D01*
G01X-97100Y-228700D02*
Y-218075D01*
X-96683Y-217034D01*
X-95850Y-216408D01*
X-94600Y-216200D01*
X-93350Y-216617D01*
X-92725Y-217658D01*
G01X-95225Y-221200D02*
X-99392D01*
G01X-80350Y-228700D02*
X-81600Y-228492D01*
X-82850Y-227659D01*
X-83684Y-226200D01*
X-84100Y-224533D01*
X-83684Y-222867D01*
X-82850Y-221408D01*
X-81600Y-220575D01*
X-80350Y-220367D01*
X-79100Y-220575D01*
X-77850Y-221408D01*
X-77017Y-222867D01*
X-76808Y-224533D01*
X-77017Y-226200D01*
X-77850Y-227659D01*
X-79100Y-228492D01*
X-80350Y-228700D01*
G01X-64850D02*
Y-216200D01*
G01X-49350Y-228700D02*
Y-216200D01*
G01X-33850Y-228700D02*
X-35100Y-228492D01*
X-36350Y-227659D01*
X-37184Y-226200D01*
X-37600Y-224533D01*
X-37184Y-222867D01*
X-36350Y-221408D01*
X-35100Y-220575D01*
X-33850Y-220367D01*
X-32600Y-220575D01*
X-31350Y-221408D01*
X-30517Y-222867D01*
X-30308Y-224533D01*
X-30517Y-226200D01*
X-31350Y-227659D01*
X-32600Y-228492D01*
X-33850Y-228700D01*
G01X-23559Y-220367D02*
X-21058Y-228700D01*
X-18350Y-220367D01*
X-15642Y-228700D01*
X-13141Y-220367D01*
G01X9733Y-231825D02*
X11192Y-232658D01*
X12858Y-232867D01*
X14317Y-232658D01*
X15567Y-231617D01*
X16400Y-230158D01*
Y-220367D01*
G01Y-222033D02*
X15567Y-221200D01*
X14317Y-220575D01*
X12858Y-220367D01*
X11192Y-220783D01*
X10150Y-221617D01*
X9316Y-223075D01*
X8900Y-224533D01*
X9108Y-225784D01*
X9942Y-227242D01*
X11192Y-228283D01*
X12858Y-228700D01*
X14108Y-228492D01*
X15567Y-227659D01*
X16400Y-226825D01*
G01X25025Y-223075D02*
X31692D01*
X31067Y-221617D01*
X30025Y-220783D01*
X28567Y-220367D01*
X27108Y-220575D01*
X25858Y-221200D01*
X25025Y-222658D01*
X24608Y-223909D01*
Y-225158D01*
X25025Y-226408D01*
X26067Y-227659D01*
X27317Y-228492D01*
X28775Y-228700D01*
X30233Y-228283D01*
X31692Y-227034D01*
G01X40733Y-228700D02*
Y-220367D01*
G01Y-222033D02*
X41775Y-221200D01*
X42817Y-220575D01*
X44275Y-220367D01*
X45317Y-220575D01*
X46567Y-221200D01*
G01X55400Y-228700D02*
Y-216200D01*
G01Y-222450D02*
X56442Y-221200D01*
X57692Y-220575D01*
X58942Y-220367D01*
X60817Y-220783D01*
X62067Y-221617D01*
X62900Y-223075D01*
Y-224742D01*
X62483Y-226408D01*
X61650Y-227659D01*
X60192Y-228492D01*
X58942Y-228700D01*
X57692Y-228492D01*
X56442Y-227867D01*
X55400Y-226825D01*
G01X71525Y-223075D02*
X78192D01*
X77567Y-221617D01*
X76525Y-220783D01*
X75067Y-220367D01*
X73608Y-220575D01*
X72358Y-221200D01*
X71525Y-222658D01*
X71108Y-223909D01*
Y-225158D01*
X71525Y-226408D01*
X72567Y-227659D01*
X73817Y-228492D01*
X75275Y-228700D01*
X76733Y-228283D01*
X78192Y-227034D01*
G01X87233Y-228700D02*
Y-220367D01*
G01Y-222033D02*
X88275Y-221200D01*
X89317Y-220575D01*
X90775Y-220367D01*
X91817Y-220575D01*
X93067Y-221200D01*
G01X124900Y-216200D02*
Y-228700D01*
G01Y-226825D02*
X124067Y-227867D01*
X122817Y-228492D01*
X121358Y-228700D01*
X119692Y-228283D01*
X118442Y-227242D01*
X117608Y-225992D01*
X117400Y-224533D01*
X117608Y-223075D01*
X118442Y-221825D01*
X119692Y-220783D01*
X121358Y-220367D01*
X122817Y-220575D01*
X123858Y-220992D01*
X124900Y-221825D01*
G01X133525Y-223075D02*
X140192D01*
X139567Y-221617D01*
X138525Y-220783D01*
X137067Y-220367D01*
X135608Y-220575D01*
X134358Y-221200D01*
X133525Y-222658D01*
X133108Y-223909D01*
Y-225158D01*
X133525Y-226408D01*
X134567Y-227659D01*
X135817Y-228492D01*
X137275Y-228700D01*
X138733Y-228283D01*
X140192Y-227034D01*
G01X149025Y-227242D02*
X150067Y-228075D01*
X151525Y-228700D01*
X152775D01*
X154025Y-228283D01*
X154858Y-227659D01*
X155275Y-226825D01*
X155067Y-225575D01*
X154233Y-224950D01*
X150483Y-223700D01*
X149650Y-222242D01*
X150067Y-221200D01*
X150900Y-220575D01*
X152150Y-220367D01*
X153400Y-220575D01*
X154650Y-221200D01*
G01X167650Y-220367D02*
Y-228700D01*
G01Y-217034D02*
X167233Y-216825D01*
Y-216408D01*
X167650Y-216200D01*
X168067Y-216408D01*
Y-216825D01*
X167650Y-217034D01*
G01X180233Y-231825D02*
X181692Y-232658D01*
X183358Y-232867D01*
X184817Y-232658D01*
X186067Y-231617D01*
X186900Y-230158D01*
Y-220367D01*
G01Y-222033D02*
X186067Y-221200D01*
X184817Y-220575D01*
X183358Y-220367D01*
X181692Y-220783D01*
X180650Y-221617D01*
X179816Y-223075D01*
X179400Y-224533D01*
X179608Y-225784D01*
X180442Y-227242D01*
X181692Y-228283D01*
X183358Y-228700D01*
X184608Y-228492D01*
X186067Y-227659D01*
X186900Y-226825D01*
G01X195108Y-228700D02*
Y-220367D01*
G01Y-222450D02*
X195942Y-221408D01*
X197192Y-220575D01*
X198858Y-220367D01*
X200317Y-220575D01*
X201567Y-221408D01*
X202192Y-222867D01*
Y-228700D01*
G01X-29933Y92900D02*
Y105400D01*
X-25767D01*
X-24100Y104775D01*
X-22850Y103942D01*
X-21808Y102692D01*
X-20975Y101233D01*
X-20767Y99150D01*
X-20975Y97067D01*
X-21808Y95608D01*
X-22850Y94358D01*
X-24100Y93525D01*
X-25767Y92900D01*
X-29933D01*
G01X-12975Y98525D02*
X-6308D01*
X-6933Y99983D01*
X-7975Y100817D01*
X-9433Y101233D01*
X-10892Y101025D01*
X-12142Y100400D01*
X-12975Y98942D01*
X-13392Y97691D01*
Y96442D01*
X-12975Y95192D01*
X-11933Y93941D01*
X-10683Y93108D01*
X-9225Y92900D01*
X-7767Y93317D01*
X-6308Y94566D01*
G01X4400Y92900D02*
Y103525D01*
X4817Y104566D01*
X5650Y105192D01*
X6900Y105400D01*
X8150Y104983D01*
X8775Y103942D01*
G01X6275Y100400D02*
X2108D01*
G01X21150Y101233D02*
Y92900D01*
G01Y104566D02*
X20733Y104775D01*
Y105192D01*
X21150Y105400D01*
X21567Y105192D01*
Y104775D01*
X21150Y104566D01*
G01X33108Y92900D02*
Y101233D01*
G01Y99150D02*
X33942Y100192D01*
X35192Y101025D01*
X36858Y101233D01*
X38317Y101025D01*
X39567Y100192D01*
X40192Y98733D01*
Y92900D01*
G01X49025Y98525D02*
X55692D01*
X55067Y99983D01*
X54025Y100817D01*
X52567Y101233D01*
X51108Y101025D01*
X49858Y100400D01*
X49025Y98942D01*
X48608Y97691D01*
Y96442D01*
X49025Y95192D01*
X50067Y93941D01*
X51317Y93108D01*
X52775Y92900D01*
X54233Y93317D01*
X55692Y94566D01*
G01X83150Y105400D02*
Y92900D01*
G01X80233Y101233D02*
X86067D01*
G01X95108Y92900D02*
Y105400D01*
G01Y99358D02*
X96150Y100400D01*
X97192Y101025D01*
X98858Y101233D01*
X100108Y101025D01*
X101567Y100192D01*
X102192Y98942D01*
Y92900D01*
G01X111025Y98525D02*
X117692D01*
X117067Y99983D01*
X116025Y100817D01*
X114567Y101233D01*
X113108Y101025D01*
X111858Y100400D01*
X111025Y98942D01*
X110608Y97691D01*
Y96442D01*
X111025Y95192D01*
X112067Y93941D01*
X113317Y93108D01*
X114775Y92900D01*
X116233Y93317D01*
X117692Y94566D01*
G01X126733Y92900D02*
Y101233D01*
G01Y99567D02*
X127775Y100400D01*
X128817Y101025D01*
X130275Y101233D01*
X131317Y101025D01*
X132567Y100400D01*
G01X138900Y92900D02*
Y101233D01*
G01Y98942D02*
X139525Y99983D01*
X140567Y100817D01*
X142025Y101233D01*
X143483Y100817D01*
X144525Y99983D01*
X145150Y98942D01*
Y92900D01*
G01Y98942D02*
X145775Y99983D01*
X146817Y100817D01*
X148275Y101233D01*
X149733Y100817D01*
X150775Y99983D01*
X151400Y98733D01*
Y92900D01*
G01X164400D02*
Y101233D01*
G01Y99775D02*
X163567Y100608D01*
X162317Y101025D01*
X160858Y101233D01*
X159400Y100817D01*
X158150Y99983D01*
X157316Y98733D01*
X156900Y97067D01*
X157316Y95400D01*
X158150Y94150D01*
X159400Y93317D01*
X160858Y92900D01*
X162317Y93108D01*
X163567Y93733D01*
X164400Y94566D01*
G01X176150Y92900D02*
Y105400D01*
G01X204233Y92900D02*
Y101233D01*
G01Y99567D02*
X205275Y100400D01*
X206317Y101025D01*
X207775Y101233D01*
X208817Y101025D01*
X210067Y100400D01*
G01X219525Y98525D02*
X226192D01*
X225567Y99983D01*
X224525Y100817D01*
X223067Y101233D01*
X221608Y101025D01*
X220358Y100400D01*
X219525Y98942D01*
X219108Y97691D01*
Y96442D01*
X219525Y95192D01*
X220567Y93941D01*
X221817Y93108D01*
X223275Y92900D01*
X224733Y93317D01*
X226192Y94566D01*
G01X238150Y92900D02*
Y105400D01*
G01X253650Y101233D02*
Y92900D01*
G01Y104566D02*
X253233Y104775D01*
Y105192D01*
X253650Y105400D01*
X254067Y105192D01*
Y104775D01*
X253650Y104566D01*
G01X266025Y98525D02*
X272692D01*
X272067Y99983D01*
X271025Y100817D01*
X269567Y101233D01*
X268108Y101025D01*
X266858Y100400D01*
X266025Y98942D01*
X265608Y97691D01*
Y96442D01*
X266025Y95192D01*
X267067Y93941D01*
X268317Y93108D01*
X269775Y92900D01*
X271233Y93317D01*
X272692Y94566D01*
G01X283400Y92900D02*
Y103525D01*
X283817Y104566D01*
X284650Y105192D01*
X285900Y105400D01*
X287150Y104983D01*
X287775Y103942D01*
G01X285275Y100400D02*
X281108D01*
G01X318983Y100192D02*
X317525Y101025D01*
X316275Y101233D01*
X314608Y100817D01*
X313358Y99983D01*
X312525Y98525D01*
X312316Y97067D01*
X312525Y95608D01*
X313358Y94358D01*
X314608Y93317D01*
X316275Y92900D01*
X317733Y93317D01*
X318983Y94150D01*
G01X331150Y92900D02*
X329900Y93108D01*
X328650Y93941D01*
X327816Y95400D01*
X327400Y97067D01*
X327816Y98733D01*
X328650Y100192D01*
X329900Y101025D01*
X331150Y101233D01*
X332400Y101025D01*
X333650Y100192D01*
X334483Y98733D01*
X334692Y97067D01*
X334483Y95400D01*
X333650Y93941D01*
X332400Y93108D01*
X331150Y92900D01*
G01X343108D02*
Y101233D01*
G01Y99150D02*
X343942Y100192D01*
X345192Y101025D01*
X346858Y101233D01*
X348317Y101025D01*
X349567Y100192D01*
X350192Y98733D01*
Y92900D01*
G01X358608D02*
Y101233D01*
G01Y99150D02*
X359442Y100192D01*
X360692Y101025D01*
X362358Y101233D01*
X363817Y101025D01*
X365067Y100192D01*
X365692Y98733D01*
Y92900D01*
G01X374525Y98525D02*
X381192D01*
X380567Y99983D01*
X379525Y100817D01*
X378067Y101233D01*
X376608Y101025D01*
X375358Y100400D01*
X374525Y98942D01*
X374108Y97691D01*
Y96442D01*
X374525Y95192D01*
X375567Y93941D01*
X376817Y93108D01*
X378275Y92900D01*
X379733Y93317D01*
X381192Y94566D01*
G01X396483Y100192D02*
X395025Y101025D01*
X393775Y101233D01*
X392108Y100817D01*
X390858Y99983D01*
X390025Y98525D01*
X389816Y97067D01*
X390025Y95608D01*
X390858Y94358D01*
X392108Y93317D01*
X393775Y92900D01*
X395233Y93317D01*
X396483Y94150D01*
G01X408650Y105400D02*
Y92900D01*
G01X405733Y101233D02*
X411567D01*
G01X642167Y-335717D02*
X651333Y-326550D01*
G01X646750Y-324883D02*
Y-337383D01*
G01X651333Y-335717D02*
X642167Y-326550D01*
G01X640500Y-331133D02*
X653000D01*
G01X657667Y-335717D02*
X666833Y-326550D01*
G01X662250Y-324883D02*
Y-337383D01*
G01X666833Y-335717D02*
X657667Y-326550D01*
G01X656000Y-331133D02*
X668500D01*
G01X673167Y-335717D02*
X682333Y-326550D01*
G01X677750Y-324883D02*
Y-337383D01*
G01X682333Y-335717D02*
X673167Y-326550D01*
G01X671500Y-331133D02*
X684000D01*
G01X688667Y-335717D02*
X697833Y-326550D01*
G01X693250Y-324883D02*
Y-337383D01*
G01X697833Y-335717D02*
X688667Y-326550D01*
G01X687000Y-331133D02*
X699500D01*
G01X708750Y-335717D02*
X708333Y-335508D01*
Y-335092D01*
X708750Y-334883D01*
X709167Y-335092D01*
Y-335508D01*
X708750Y-335717D01*
G01Y-330092D02*
X708333Y-329883D01*
Y-329467D01*
X708750Y-329258D01*
X709167Y-329467D01*
Y-329883D01*
X708750Y-330092D01*
G01X737250Y-322800D02*
X742250D01*
G01X739750D02*
Y-335300D01*
G01X737250D02*
X742250D01*
G01X752333Y-338425D02*
X753792Y-339258D01*
X755458Y-339467D01*
X756917Y-339258D01*
X758167Y-338217D01*
X759000Y-336758D01*
Y-326967D01*
G01Y-328633D02*
X758167Y-327800D01*
X756917Y-327175D01*
X755458Y-326967D01*
X753792Y-327383D01*
X752750Y-328217D01*
X751916Y-329675D01*
X751500Y-331133D01*
X751708Y-332384D01*
X752542Y-333842D01*
X753792Y-334883D01*
X755458Y-335300D01*
X756708Y-335092D01*
X758167Y-334259D01*
X759000Y-333425D01*
G01X767208Y-335300D02*
Y-326967D01*
G01Y-329050D02*
X768042Y-328008D01*
X769292Y-327175D01*
X770958Y-326967D01*
X772417Y-327175D01*
X773667Y-328008D01*
X774292Y-329467D01*
Y-335300D01*
G01X786250D02*
X785000Y-335092D01*
X783750Y-334259D01*
X782916Y-332800D01*
X782500Y-331133D01*
X782916Y-329467D01*
X783750Y-328008D01*
X785000Y-327175D01*
X786250Y-326967D01*
X787500Y-327175D01*
X788750Y-328008D01*
X789583Y-329467D01*
X789792Y-331133D01*
X789583Y-332800D01*
X788750Y-334259D01*
X787500Y-335092D01*
X786250Y-335300D01*
G01X798833D02*
Y-326967D01*
G01Y-328633D02*
X799875Y-327800D01*
X800917Y-327175D01*
X802375Y-326967D01*
X803417Y-327175D01*
X804667Y-327800D01*
G01X814125Y-329675D02*
X820792D01*
X820167Y-328217D01*
X819125Y-327383D01*
X817667Y-326967D01*
X816208Y-327175D01*
X814958Y-327800D01*
X814125Y-329258D01*
X813708Y-330509D01*
Y-331758D01*
X814125Y-333008D01*
X815167Y-334259D01*
X816417Y-335092D01*
X817875Y-335300D01*
X819333Y-334883D01*
X820792Y-333634D01*
G01X848250Y-335300D02*
Y-322800D01*
X845750Y-325300D01*
G01Y-335300D02*
X850750D01*
G01X873000D02*
Y-326967D01*
G01Y-329258D02*
X873625Y-328217D01*
X874667Y-327383D01*
X876125Y-326967D01*
X877583Y-327383D01*
X878625Y-328217D01*
X879250Y-329258D01*
Y-335300D01*
G01Y-329258D02*
X879875Y-328217D01*
X880917Y-327383D01*
X882375Y-326967D01*
X883833Y-327383D01*
X884875Y-328217D01*
X885500Y-329467D01*
Y-335300D01*
G01X894750Y-326967D02*
Y-335300D01*
G01Y-323634D02*
X894333Y-323425D01*
Y-323008D01*
X894750Y-322800D01*
X895167Y-323008D01*
Y-323425D01*
X894750Y-323634D01*
G01X910250Y-335300D02*
Y-322800D01*
G01X936667Y-335300D02*
Y-322800D01*
X940833D01*
X942500Y-323425D01*
X943750Y-324258D01*
X944792Y-325508D01*
X945625Y-326967D01*
X945833Y-329050D01*
X945625Y-331133D01*
X944792Y-332592D01*
X943750Y-333842D01*
X942500Y-334675D01*
X940833Y-335300D01*
X936667D01*
G01X954042Y-331133D02*
X959458D01*
G01X976833Y-323842D02*
X975583Y-323217D01*
X974125Y-322800D01*
X972458D01*
X970583Y-323425D01*
X969125Y-324467D01*
X968083Y-325717D01*
X967250Y-327800D01*
X967041Y-329675D01*
X967458Y-331550D01*
X968083Y-332800D01*
X969333Y-334050D01*
X970792Y-334883D01*
X972250Y-335300D01*
X973708D01*
X975167Y-334883D01*
X976417Y-334259D01*
X977459Y-333425D01*
G01X987750Y-335300D02*
X986083Y-335092D01*
X984625Y-334259D01*
X983375Y-333008D01*
X982541Y-331550D01*
X982125Y-329883D01*
Y-328217D01*
X982541Y-326550D01*
X983375Y-325092D01*
X984625Y-323842D01*
X986083Y-323008D01*
X987750Y-322800D01*
X989417Y-323008D01*
X990875Y-323842D01*
X992125Y-325092D01*
X992959Y-326550D01*
X993375Y-328217D01*
Y-329883D01*
X992959Y-331550D01*
X992125Y-333008D01*
X990875Y-334259D01*
X989417Y-335092D01*
X987750Y-335300D01*
G01X998667D02*
Y-322800D01*
X1002833D01*
X1004500Y-323425D01*
X1005750Y-324258D01*
X1006792Y-325508D01*
X1007625Y-326967D01*
X1007833Y-329050D01*
X1007625Y-331133D01*
X1006792Y-332592D01*
X1005750Y-333842D01*
X1004500Y-334675D01*
X1002833Y-335300D01*
X998667D01*
G01X1022917D02*
X1014583D01*
Y-322800D01*
X1022917D01*
G01X1019583Y-328842D02*
X1014583D01*
G01X646358Y-290400D02*
Y-277900D01*
X655942Y-290400D01*
Y-277900D01*
G01X666650Y-290400D02*
X665400Y-290192D01*
X664150Y-289359D01*
X663316Y-287900D01*
X662900Y-286233D01*
X663316Y-284567D01*
X664150Y-283108D01*
X665400Y-282275D01*
X666650Y-282067D01*
X667900Y-282275D01*
X669150Y-283108D01*
X669983Y-284567D01*
X670192Y-286233D01*
X669983Y-287900D01*
X669150Y-289359D01*
X667900Y-290192D01*
X666650Y-290400D01*
G01X682150Y-277900D02*
Y-290400D01*
G01X679233Y-282067D02*
X685067D01*
G01X694525Y-284775D02*
X701192D01*
X700567Y-283317D01*
X699525Y-282483D01*
X698067Y-282067D01*
X696608Y-282275D01*
X695358Y-282900D01*
X694525Y-284358D01*
X694108Y-285609D01*
Y-286858D01*
X694525Y-288108D01*
X695567Y-289359D01*
X696817Y-290192D01*
X698275Y-290400D01*
X699733Y-289983D01*
X701192Y-288734D01*
G01X710025Y-288942D02*
X711067Y-289775D01*
X712525Y-290400D01*
X713775D01*
X715025Y-289983D01*
X715858Y-289359D01*
X716275Y-288525D01*
X716067Y-287275D01*
X715233Y-286650D01*
X711483Y-285400D01*
X710650Y-283942D01*
X711067Y-282900D01*
X711900Y-282275D01*
X713150Y-282067D01*
X714400Y-282275D01*
X715650Y-282900D01*
G01X728650Y-290817D02*
X728233Y-290608D01*
Y-290192D01*
X728650Y-289983D01*
X729067Y-290192D01*
Y-290608D01*
X728650Y-290817D01*
G01Y-285192D02*
X728233Y-284983D01*
Y-284567D01*
X728650Y-284358D01*
X729067Y-284567D01*
Y-284983D01*
X728650Y-285192D01*
G54D11*
G01X-25267Y-107100D02*
X-31933D01*
Y-97100D01*
X-25267D01*
G01X-27933Y-101933D02*
X-31933D01*
G01X-20800Y-107100D02*
X-13800Y-97100D01*
G01X-20800D02*
X-13800Y-107100D01*
G01X-6000Y-107433D02*
X-6333Y-107267D01*
Y-106933D01*
X-6000Y-106767D01*
X-5667Y-106933D01*
Y-107267D01*
X-6000Y-107433D01*
G01Y-102934D02*
X-6333Y-102767D01*
Y-102433D01*
X-6000Y-102267D01*
X-5667Y-102433D01*
Y-102767D01*
X-6000Y-102934D01*
G01X13433Y-107100D02*
Y-97100D01*
X19767D01*
G01X17433Y-101933D02*
X13433D01*
G01X24567Y-97100D02*
Y-107100D01*
X31233D01*
G01X35033D02*
X39200Y-97100D01*
X43367Y-107100D01*
G01X41867Y-103600D02*
X36533D01*
G01X47000Y-105767D02*
X48333Y-106600D01*
X49833Y-107100D01*
X51167D01*
X52500Y-106600D01*
X53500Y-105767D01*
X54000Y-104600D01*
X53667Y-103434D01*
X52833Y-102433D01*
X51333Y-101767D01*
X49333Y-101433D01*
X48167Y-100767D01*
X47667Y-99600D01*
X48000Y-98433D01*
X48833Y-97600D01*
X50000Y-97100D01*
X51167D01*
X52333Y-97433D01*
X53333Y-98267D01*
G01X58300Y-107100D02*
Y-97100D01*
G01X65300D02*
Y-107100D01*
G01Y-102100D02*
X58300D01*
G01X84400Y-97100D02*
Y-107100D01*
G01X80567Y-97100D02*
X88233D01*
G01X92367Y-107100D02*
Y-97100D01*
X96533D01*
X97867Y-97600D01*
X98700Y-98267D01*
X99033Y-99600D01*
X98700Y-100933D01*
X97700Y-101767D01*
X96533Y-102267D01*
X92367D01*
G01X96533D02*
X99033Y-107100D01*
G01X107000D02*
Y-97100D01*
X105000Y-99100D01*
G01Y-107100D02*
X109000D01*
G01X118300Y-97100D02*
X116966Y-97433D01*
X115967Y-98267D01*
X115300Y-99267D01*
X114800Y-100600D01*
X114633Y-102100D01*
X114800Y-103600D01*
X115300Y-104933D01*
X115967Y-105934D01*
X116966Y-106767D01*
X118300Y-107100D01*
X119633Y-106767D01*
X120633Y-105934D01*
X121300Y-104933D01*
X121800Y-103600D01*
X121967Y-102100D01*
X121800Y-100600D01*
X121300Y-99267D01*
X120633Y-98267D01*
X119633Y-97433D01*
X118300Y-97100D01*
G01X125933Y-105100D02*
X126933Y-106267D01*
X128266Y-106933D01*
X129767Y-107100D01*
X131100Y-106933D01*
X132433Y-106100D01*
X133267Y-105100D01*
X133433Y-104100D01*
X133100Y-102934D01*
X131933Y-102100D01*
X130767Y-101767D01*
X129267D01*
G01X130767D02*
X131767Y-101267D01*
X132600Y-100434D01*
X132933Y-99433D01*
X132600Y-98433D01*
X131767Y-97600D01*
X130267Y-97100D01*
X128767Y-97267D01*
X127267Y-97933D01*
G01X135900Y-110433D02*
X145900D01*
G01X149367Y-105934D02*
X150533Y-106767D01*
X151867Y-107100D01*
X153200Y-106767D01*
X154367Y-105767D01*
X155200Y-104267D01*
X155533Y-102767D01*
Y-100933D01*
X155200Y-99433D01*
X154367Y-98100D01*
X153367Y-97433D01*
X152200Y-97100D01*
X150866Y-97433D01*
X149867Y-98100D01*
X149200Y-99100D01*
X148867Y-100434D01*
X149200Y-101600D01*
X150033Y-102767D01*
X151033Y-103434D01*
X152200Y-103600D01*
X153533Y-103267D01*
X154533Y-102433D01*
X155533Y-100933D01*
G01X159833Y-105100D02*
X160833Y-106267D01*
X162166Y-106933D01*
X163667Y-107100D01*
X165000Y-106933D01*
X166333Y-106100D01*
X167167Y-105100D01*
X167333Y-104100D01*
X167000Y-102934D01*
X165833Y-102100D01*
X164667Y-101767D01*
X163167D01*
G01X164667D02*
X165667Y-101267D01*
X166500Y-100434D01*
X166833Y-99433D01*
X166500Y-98433D01*
X165667Y-97600D01*
X164167Y-97100D01*
X162667Y-97267D01*
X161167Y-97933D01*
G01X169800Y-110433D02*
X179800D01*
G01X182433Y-105100D02*
X183433Y-106267D01*
X184766Y-106933D01*
X186267Y-107100D01*
X187600Y-106933D01*
X188933Y-106100D01*
X189767Y-105100D01*
X189933Y-104100D01*
X189600Y-102934D01*
X188433Y-102100D01*
X187267Y-101767D01*
X185767D01*
G01X187267D02*
X188267Y-101267D01*
X189100Y-100434D01*
X189433Y-99433D01*
X189100Y-98433D01*
X188267Y-97600D01*
X186767Y-97100D01*
X185267Y-97267D01*
X183767Y-97933D01*
G01X197400Y-97100D02*
X196066Y-97433D01*
X195067Y-98267D01*
X194400Y-99267D01*
X193900Y-100600D01*
X193733Y-102100D01*
X193900Y-103600D01*
X194400Y-104933D01*
X195067Y-105934D01*
X196066Y-106767D01*
X197400Y-107100D01*
X198733Y-106767D01*
X199733Y-105934D01*
X200400Y-104933D01*
X200900Y-103600D01*
X201067Y-102100D01*
X200900Y-100600D01*
X200400Y-99267D01*
X199733Y-98267D01*
X198733Y-97433D01*
X197400Y-97100D01*
G01X208700Y-107433D02*
X208367Y-107267D01*
Y-106933D01*
X208700Y-106767D01*
X209033Y-106933D01*
Y-107267D01*
X208700Y-107433D01*
G01Y-102934D02*
X208367Y-102767D01*
Y-102433D01*
X208700Y-102267D01*
X209033Y-102433D01*
Y-102767D01*
X208700Y-102934D01*
G01X-18267Y34900D02*
X-17267Y33733D01*
X-15934Y33067D01*
X-14433Y32900D01*
X-13100Y33067D01*
X-11767Y33900D01*
X-10933Y34900D01*
X-10767Y35900D01*
X-11100Y37066D01*
X-12267Y37900D01*
X-13433Y38233D01*
X-14933D01*
G01X-13433D02*
X-12433Y38733D01*
X-11600Y39566D01*
X-11267Y40567D01*
X-11600Y41567D01*
X-12433Y42400D01*
X-13933Y42900D01*
X-15433Y42733D01*
X-16933Y42067D01*
G01X-3300Y32567D02*
X-3633Y32733D01*
Y33067D01*
X-3300Y33233D01*
X-2967Y33067D01*
Y32733D01*
X-3300Y32567D01*
G01X-17767Y57233D02*
X-16767Y58233D01*
X-15600Y58733D01*
X-14267Y58900D01*
X-12600Y58567D01*
X-11433Y57733D01*
X-11100Y56733D01*
X-11267Y55733D01*
X-11933Y54900D01*
X-15267Y53233D01*
X-16767Y52067D01*
X-17767Y50400D01*
X-18100Y48900D01*
X-11100D01*
G01X-3300Y48567D02*
X-3633Y48733D01*
Y49067D01*
X-3300Y49233D01*
X-2967Y49067D01*
Y48733D01*
X-3300Y48567D01*
G01X-14600Y64900D02*
Y74900D01*
X-16600Y72900D01*
G01Y64900D02*
X-12600D01*
G01X-3300Y64567D02*
X-3633Y64733D01*
Y65067D01*
X-3300Y65233D01*
X-2967Y65067D01*
Y64733D01*
X-3300Y64567D01*
G01X16133Y64900D02*
Y74900D01*
X22467D01*
G01X20133Y70067D02*
X16133D01*
G01X27267Y74900D02*
Y64900D01*
X33933D01*
G01X37733D02*
X41900Y74900D01*
X46067Y64900D01*
G01X44567Y68400D02*
X39233D01*
G01X49700Y66233D02*
X51033Y65400D01*
X52533Y64900D01*
X53867D01*
X55200Y65400D01*
X56200Y66233D01*
X56700Y67400D01*
X56367Y68566D01*
X55533Y69567D01*
X54033Y70233D01*
X52033Y70567D01*
X50867Y71233D01*
X50367Y72400D01*
X50700Y73567D01*
X51533Y74400D01*
X52700Y74900D01*
X53867D01*
X55033Y74567D01*
X56033Y73733D01*
G01X61000Y64900D02*
Y74900D01*
G01X68000D02*
Y64900D01*
G01Y69900D02*
X61000D01*
G01X87100Y74900D02*
Y64900D01*
G01X83267Y74900D02*
X90933D01*
G01X94900Y64900D02*
Y74900D01*
G01X101900D02*
Y64900D01*
G01Y69900D02*
X94900D01*
G01X105367Y64900D02*
Y74900D01*
X109700Y66567D01*
X114033Y74900D01*
Y64900D01*
G01X117667Y74900D02*
Y64900D01*
X124333D01*
G01X132300D02*
Y74900D01*
X130300Y72900D01*
G01Y64900D02*
X134300D01*
G01X143600Y74900D02*
X142266Y74567D01*
X141267Y73733D01*
X140600Y72733D01*
X140100Y71400D01*
X139933Y69900D01*
X140100Y68400D01*
X140600Y67067D01*
X141267Y66066D01*
X142266Y65233D01*
X143600Y64900D01*
X144933Y65233D01*
X145933Y66066D01*
X146600Y67067D01*
X147100Y68400D01*
X147267Y69900D01*
X147100Y71400D01*
X146600Y72733D01*
X145933Y73733D01*
X144933Y74567D01*
X143600Y74900D01*
G01X166200Y64567D02*
X165867Y64733D01*
Y65067D01*
X166200Y65233D01*
X166533Y65067D01*
Y64733D01*
X166200Y64567D01*
G01Y69066D02*
X165867Y69233D01*
Y69567D01*
X166200Y69733D01*
X166533Y69567D01*
Y69233D01*
X166200Y69066D01*
G01X185633Y64900D02*
Y74900D01*
X191967D01*
G01X189633Y70067D02*
X185633D01*
G01X197267Y71566D02*
Y66900D01*
X197933Y65733D01*
X198933Y65067D01*
X200100Y64900D01*
X201267Y65067D01*
X202267Y65733D01*
X202933Y66900D01*
G01Y64900D02*
Y71566D01*
G01X211400Y64900D02*
Y74900D01*
G01X222700Y64900D02*
Y74900D01*
G01X247967Y70733D02*
X246800Y71400D01*
X245800Y71566D01*
X244467Y71233D01*
X243467Y70567D01*
X242800Y69400D01*
X242633Y68233D01*
X242800Y67067D01*
X243467Y66066D01*
X244467Y65233D01*
X245800Y64900D01*
X246967Y65233D01*
X247967Y65900D01*
G01X256600Y64900D02*
X255600Y65067D01*
X254600Y65733D01*
X253933Y66900D01*
X253600Y68233D01*
X253933Y69567D01*
X254600Y70733D01*
X255600Y71400D01*
X256600Y71566D01*
X257600Y71400D01*
X258600Y70733D01*
X259267Y69567D01*
X259433Y68233D01*
X259267Y66900D01*
X258600Y65733D01*
X257600Y65067D01*
X256600Y64900D01*
G01X265067D02*
Y71566D01*
G01Y69900D02*
X265733Y70733D01*
X266733Y71400D01*
X268067Y71566D01*
X269233Y71400D01*
X270233Y70733D01*
X270733Y69567D01*
Y64900D01*
G01X279200Y74900D02*
Y64900D01*
G01X276867Y71566D02*
X281533D01*
G01X293500Y64900D02*
Y71566D01*
G01Y70400D02*
X292833Y71067D01*
X291833Y71400D01*
X290667Y71566D01*
X289500Y71233D01*
X288500Y70567D01*
X287833Y69567D01*
X287500Y68233D01*
X287833Y66900D01*
X288500Y65900D01*
X289500Y65233D01*
X290667Y64900D01*
X291833Y65067D01*
X292833Y65567D01*
X293500Y66233D01*
G01X304467Y70733D02*
X303300Y71400D01*
X302300Y71566D01*
X300967Y71233D01*
X299967Y70567D01*
X299300Y69400D01*
X299133Y68233D01*
X299300Y67067D01*
X299967Y66066D01*
X300967Y65233D01*
X302300Y64900D01*
X303467Y65233D01*
X304467Y65900D01*
G01X313100Y74900D02*
Y64900D01*
G01X310767Y71566D02*
X315433D01*
G01X47733Y-601800D02*
X41067D01*
Y-591800D01*
X47733D01*
G01X45067Y-596633D02*
X41067D01*
G01X55700Y-602133D02*
X55367Y-601967D01*
Y-601633D01*
X55700Y-601467D01*
X56033Y-601633D01*
Y-601967D01*
X55700Y-602133D01*
G01Y-597634D02*
X55367Y-597467D01*
Y-597133D01*
X55700Y-596967D01*
X56033Y-597133D01*
Y-597467D01*
X55700Y-597634D01*
G01X31033Y-627800D02*
X24367D01*
Y-617800D01*
X31033D01*
G01X28367Y-622633D02*
X24367D01*
G01X35500Y-627800D02*
X42500Y-617800D01*
G01X35500D02*
X42500Y-627800D01*
G01X50300Y-628133D02*
X49967Y-627967D01*
Y-627633D01*
X50300Y-627467D01*
X50633Y-627633D01*
Y-627967D01*
X50300Y-628133D01*
G01Y-623634D02*
X49967Y-623467D01*
Y-623133D01*
X50300Y-622967D01*
X50633Y-623133D01*
Y-623467D01*
X50300Y-623634D01*
G01X69733Y-627800D02*
Y-617800D01*
X76067D01*
G01X73733Y-622633D02*
X69733D01*
G01X80867Y-617800D02*
Y-627800D01*
X87533D01*
G01X91333D02*
X95500Y-617800D01*
X99667Y-627800D01*
G01X98167Y-624300D02*
X92833D01*
G01X103300Y-626467D02*
X104633Y-627300D01*
X106133Y-627800D01*
X107467D01*
X108800Y-627300D01*
X109800Y-626467D01*
X110300Y-625300D01*
X109967Y-624134D01*
X109133Y-623133D01*
X107633Y-622467D01*
X105633Y-622133D01*
X104467Y-621467D01*
X103967Y-620300D01*
X104300Y-619133D01*
X105133Y-618300D01*
X106300Y-617800D01*
X107467D01*
X108633Y-618133D01*
X109633Y-618967D01*
G01X114600Y-627800D02*
Y-617800D01*
G01X121600D02*
Y-627800D01*
G01Y-622800D02*
X114600D01*
G01X140700Y-617800D02*
Y-627800D01*
G01X136867Y-617800D02*
X144533D01*
G01X148667Y-627800D02*
Y-617800D01*
X152833D01*
X154167Y-618300D01*
X155000Y-618967D01*
X155333Y-620300D01*
X155000Y-621633D01*
X154000Y-622467D01*
X152833Y-622967D01*
X148667D01*
G01X152833D02*
X155333Y-627800D01*
G01X160133Y-623634D02*
X161300Y-622467D01*
X162300Y-621800D01*
X163633Y-621467D01*
X164800Y-621800D01*
X165633Y-622467D01*
X166300Y-623467D01*
X166467Y-624633D01*
X166300Y-625633D01*
X165633Y-626634D01*
X164633Y-627467D01*
X163467Y-627800D01*
X162133Y-627467D01*
X160967Y-626467D01*
X160300Y-624967D01*
X160133Y-623300D01*
X160467Y-621134D01*
X160967Y-619967D01*
X161800Y-618800D01*
X162967Y-617967D01*
X164133Y-617800D01*
X165300Y-618133D01*
X166133Y-618967D01*
G01X174600Y-617800D02*
X173266Y-618133D01*
X172267Y-618967D01*
X171600Y-619967D01*
X171100Y-621300D01*
X170933Y-622800D01*
X171100Y-624300D01*
X171600Y-625633D01*
X172267Y-626634D01*
X173266Y-627467D01*
X174600Y-627800D01*
X175933Y-627467D01*
X176933Y-626634D01*
X177600Y-625633D01*
X178100Y-624300D01*
X178267Y-622800D01*
X178100Y-621300D01*
X177600Y-619967D01*
X176933Y-618967D01*
X175933Y-618133D01*
X174600Y-617800D01*
G01X182400Y-627800D02*
X189400Y-617800D01*
G01X182400D02*
X189400Y-627800D01*
G01X197200D02*
Y-617800D01*
X195200Y-619800D01*
G01Y-627800D02*
X199200D01*
G01X208500D02*
Y-617800D01*
X206500Y-619800D01*
G01Y-627800D02*
X210500D01*
G01X216967Y-626634D02*
X218133Y-627467D01*
X219467Y-627800D01*
X220800Y-627467D01*
X221967Y-626467D01*
X222800Y-624967D01*
X223133Y-623467D01*
Y-621633D01*
X222800Y-620133D01*
X221967Y-618800D01*
X220967Y-618133D01*
X219800Y-617800D01*
X218466Y-618133D01*
X217467Y-618800D01*
X216800Y-619800D01*
X216467Y-621134D01*
X216800Y-622300D01*
X217633Y-623467D01*
X218633Y-624134D01*
X219800Y-624300D01*
X221133Y-623967D01*
X222133Y-623133D01*
X223133Y-621633D01*
G01X226100Y-631133D02*
X236100D01*
G01X239233Y-619467D02*
X240233Y-618467D01*
X241400Y-617967D01*
X242733Y-617800D01*
X244400Y-618133D01*
X245567Y-618967D01*
X245900Y-619967D01*
X245733Y-620967D01*
X245067Y-621800D01*
X241733Y-623467D01*
X240233Y-624633D01*
X239233Y-626300D01*
X238900Y-627800D01*
X245900D01*
G01X253700Y-617800D02*
X252366Y-618133D01*
X251367Y-618967D01*
X250700Y-619967D01*
X250200Y-621300D01*
X250033Y-622800D01*
X250200Y-624300D01*
X250700Y-625633D01*
X251367Y-626634D01*
X252366Y-627467D01*
X253700Y-627800D01*
X255033Y-627467D01*
X256033Y-626634D01*
X256700Y-625633D01*
X257200Y-624300D01*
X257367Y-622800D01*
X257200Y-621300D01*
X256700Y-619967D01*
X256033Y-618967D01*
X255033Y-618133D01*
X253700Y-617800D01*
G01X261500Y-627800D02*
X268500Y-617800D01*
G01X261500D02*
X268500Y-627800D01*
G01X272633Y-625800D02*
X273633Y-626967D01*
X274966Y-627633D01*
X276467Y-627800D01*
X277800Y-627633D01*
X279133Y-626800D01*
X279967Y-625800D01*
X280133Y-624800D01*
X279800Y-623634D01*
X278633Y-622800D01*
X277467Y-622467D01*
X275967D01*
G01X277467D02*
X278467Y-621967D01*
X279300Y-621134D01*
X279633Y-620133D01*
X279300Y-619133D01*
X278467Y-618300D01*
X276967Y-617800D01*
X275467Y-617967D01*
X273967Y-618633D01*
G01X287600Y-617800D02*
X286266Y-618133D01*
X285267Y-618967D01*
X284600Y-619967D01*
X284100Y-621300D01*
X283933Y-622800D01*
X284100Y-624300D01*
X284600Y-625633D01*
X285267Y-626634D01*
X286266Y-627467D01*
X287600Y-627800D01*
X288933Y-627467D01*
X289933Y-626634D01*
X290600Y-625633D01*
X291100Y-624300D01*
X291267Y-622800D01*
X291100Y-621300D01*
X290600Y-619967D01*
X289933Y-618967D01*
X288933Y-618133D01*
X287600Y-617800D01*
G01X20667Y-578000D02*
Y-568000D01*
X28333Y-578000D01*
Y-568000D01*
G01X31633Y-578000D02*
X35800Y-568000D01*
X39967Y-578000D01*
G01X38467Y-574500D02*
X33133D01*
G01X42767Y-578000D02*
Y-568000D01*
X47100Y-576333D01*
X51433Y-568000D01*
Y-578000D01*
G01X61733D02*
X55067D01*
Y-568000D01*
X61733D01*
G01X59067Y-572833D02*
X55067D01*
G01X69700Y-578333D02*
X69367Y-578167D01*
Y-577833D01*
X69700Y-577667D01*
X70033Y-577833D01*
Y-578167D01*
X69700Y-578333D01*
G01Y-573834D02*
X69367Y-573667D01*
Y-573333D01*
X69700Y-573167D01*
X70033Y-573333D01*
Y-573667D01*
X69700Y-573834D01*
G01X92300Y-568000D02*
Y-578000D01*
G01X88467Y-568000D02*
X96133D01*
G01X100267Y-578000D02*
Y-568000D01*
X104433D01*
X105767Y-568500D01*
X106600Y-569167D01*
X106933Y-570500D01*
X106600Y-571833D01*
X105600Y-572667D01*
X104433Y-573167D01*
X100267D01*
G01X104433D02*
X106933Y-578000D01*
G01X110733D02*
X114900Y-568000D01*
X119067Y-578000D01*
G01X117567Y-574500D02*
X112233D01*
G01X122700Y-578000D02*
X129700Y-568000D01*
G01X122700D02*
X129700Y-578000D01*
G01X138833Y-572667D02*
X139500Y-572167D01*
X140000Y-571334D01*
X140333Y-570167D01*
X140000Y-569167D01*
X139333Y-568500D01*
X138167Y-568000D01*
X133667D01*
Y-578000D01*
X139167D01*
X140333Y-577333D01*
X141000Y-576333D01*
X141333Y-575167D01*
X141000Y-574000D01*
X140000Y-573000D01*
X138833Y-572667D01*
X133667D01*
G01X143800Y-581333D02*
X153800D01*
G01X163767Y-568833D02*
X162767Y-568333D01*
X161600Y-568000D01*
X160267D01*
X158766Y-568500D01*
X157600Y-569333D01*
X156767Y-570333D01*
X156100Y-572000D01*
X155933Y-573500D01*
X156267Y-575000D01*
X156767Y-576000D01*
X157767Y-577000D01*
X158933Y-577667D01*
X160100Y-578000D01*
X161267D01*
X162433Y-577667D01*
X163433Y-577167D01*
X164267Y-576500D01*
G01X167900Y-578000D02*
X174900Y-568000D01*
G01X167900D02*
X174900Y-578000D01*
G01X179033D02*
Y-568000D01*
X182367D01*
X183700Y-568500D01*
X184700Y-569167D01*
X185533Y-570167D01*
X186200Y-571334D01*
X186367Y-573000D01*
X186200Y-574667D01*
X185533Y-575833D01*
X184700Y-576834D01*
X183700Y-577500D01*
X182367Y-578000D01*
X179033D01*
G01X60233Y-512400D02*
X53567D01*
Y-502400D01*
X60233D01*
G01X57567Y-507233D02*
X53567D01*
G01X46933Y-433400D02*
Y-423400D01*
X50267D01*
X51600Y-423900D01*
X52600Y-424567D01*
X53433Y-425567D01*
X54100Y-426734D01*
X54267Y-428400D01*
X54100Y-430067D01*
X53433Y-431233D01*
X52600Y-432234D01*
X51600Y-432900D01*
X50267Y-433400D01*
X46933D01*
G01X58633Y-311800D02*
X51967D01*
Y-301800D01*
X58633D01*
G01X55967Y-306633D02*
X51967D01*
G01X63267Y-301800D02*
Y-311800D01*
X69933D01*
G01X74567Y-301800D02*
Y-311800D01*
X81233D01*
G01X87200Y-301800D02*
X91200D01*
G01X89200D02*
Y-311800D01*
G01X87200D02*
X91200D01*
G01X97167D02*
Y-301800D01*
X101167D01*
X102500Y-302300D01*
X103500Y-303467D01*
X103833Y-304800D01*
X103500Y-306133D01*
X102667Y-307133D01*
X101167Y-307634D01*
X97167D01*
G01X108300Y-310467D02*
X109633Y-311300D01*
X111133Y-311800D01*
X112467D01*
X113800Y-311300D01*
X114800Y-310467D01*
X115300Y-309300D01*
X114967Y-308134D01*
X114133Y-307133D01*
X112633Y-306467D01*
X110633Y-306133D01*
X109467Y-305467D01*
X108967Y-304300D01*
X109300Y-303133D01*
X110133Y-302300D01*
X111300Y-301800D01*
X112467D01*
X113633Y-302133D01*
X114633Y-302967D01*
G01X126433Y-311800D02*
X119767D01*
Y-301800D01*
X126433D01*
G01X123767Y-306633D02*
X119767D01*
G01X145700Y-301800D02*
Y-311800D01*
G01X141867Y-301800D02*
X149533D01*
G01X154167Y-311800D02*
Y-301800D01*
G01Y-306633D02*
X155000Y-305800D01*
X155833Y-305300D01*
X157167Y-305134D01*
X158167Y-305300D01*
X159333Y-305967D01*
X159833Y-306967D01*
Y-311800D01*
G01X165800Y-307300D02*
X171133D01*
X170633Y-306133D01*
X169800Y-305467D01*
X168633Y-305134D01*
X167467Y-305300D01*
X166467Y-305800D01*
X165800Y-306967D01*
X165467Y-307967D01*
Y-308967D01*
X165800Y-309967D01*
X166633Y-310967D01*
X167633Y-311633D01*
X168800Y-311800D01*
X169967Y-311467D01*
X171133Y-310467D01*
G01X177267Y-311800D02*
Y-305134D01*
G01Y-306467D02*
X178100Y-305800D01*
X178933Y-305300D01*
X180100Y-305134D01*
X180933Y-305300D01*
X181933Y-305800D01*
G01X185900Y-311800D02*
Y-305134D01*
G01Y-306967D02*
X186400Y-306133D01*
X187233Y-305467D01*
X188400Y-305134D01*
X189566Y-305467D01*
X190400Y-306133D01*
X190900Y-306967D01*
Y-311800D01*
G01Y-306967D02*
X191400Y-306133D01*
X192233Y-305467D01*
X193400Y-305134D01*
X194567Y-305467D01*
X195400Y-306133D01*
X195900Y-307133D01*
Y-311800D01*
G01X205200D02*
Y-305134D01*
G01Y-306300D02*
X204533Y-305633D01*
X203533Y-305300D01*
X202367Y-305134D01*
X201200Y-305467D01*
X200200Y-306133D01*
X199533Y-307133D01*
X199200Y-308467D01*
X199533Y-309800D01*
X200200Y-310800D01*
X201200Y-311467D01*
X202367Y-311800D01*
X203533Y-311633D01*
X204533Y-311133D01*
X205200Y-310467D01*
G01X213500Y-311800D02*
Y-301800D01*
G01X57100Y-69900D02*
X61100D01*
G01X59100D02*
Y-79900D01*
G01X57100D02*
X61100D01*
G01X67567D02*
Y-73234D01*
G01Y-74900D02*
X68233Y-74067D01*
X69233Y-73400D01*
X70567Y-73234D01*
X71733Y-73400D01*
X72733Y-74067D01*
X73233Y-75233D01*
Y-79900D01*
G01X78867D02*
Y-73234D01*
G01Y-74900D02*
X79533Y-74067D01*
X80533Y-73400D01*
X81867Y-73234D01*
X83033Y-73400D01*
X84033Y-74067D01*
X84533Y-75233D01*
Y-79900D01*
G01X90500Y-75400D02*
X95833D01*
X95333Y-74233D01*
X94500Y-73567D01*
X93333Y-73234D01*
X92167Y-73400D01*
X91167Y-73900D01*
X90500Y-75067D01*
X90167Y-76067D01*
Y-77067D01*
X90500Y-78067D01*
X91333Y-79067D01*
X92333Y-79733D01*
X93500Y-79900D01*
X94667Y-79567D01*
X95833Y-78567D01*
G01X101967Y-79900D02*
Y-73234D01*
G01Y-74567D02*
X102800Y-73900D01*
X103633Y-73400D01*
X104800Y-73234D01*
X105633Y-73400D01*
X106633Y-73900D01*
G01X123233Y-79900D02*
Y-69900D01*
X126567D01*
X127900Y-70400D01*
X128900Y-71067D01*
X129733Y-72067D01*
X130400Y-73234D01*
X130567Y-74900D01*
X130400Y-76567D01*
X129733Y-77733D01*
X128900Y-78734D01*
X127900Y-79400D01*
X126567Y-79900D01*
X123233D01*
G01X138200Y-73234D02*
Y-79900D01*
G01Y-70567D02*
X137867Y-70400D01*
Y-70067D01*
X138200Y-69900D01*
X138533Y-70067D01*
Y-70400D01*
X138200Y-70567D01*
G01X152500Y-79900D02*
Y-73234D01*
G01Y-74400D02*
X151833Y-73733D01*
X150833Y-73400D01*
X149667Y-73234D01*
X148500Y-73567D01*
X147500Y-74233D01*
X146833Y-75233D01*
X146500Y-76567D01*
X146833Y-77900D01*
X147500Y-78900D01*
X148500Y-79567D01*
X149667Y-79900D01*
X150833Y-79733D01*
X151833Y-79233D01*
X152500Y-78567D01*
G01X155800Y-79900D02*
Y-73234D01*
G01Y-75067D02*
X156300Y-74233D01*
X157133Y-73567D01*
X158300Y-73234D01*
X159466Y-73567D01*
X160300Y-74233D01*
X160800Y-75067D01*
Y-79900D01*
G01Y-75067D02*
X161300Y-74233D01*
X162133Y-73567D01*
X163300Y-73234D01*
X164467Y-73567D01*
X165300Y-74233D01*
X165800Y-75233D01*
Y-79900D01*
G01X169600Y-75400D02*
X174933D01*
X174433Y-74233D01*
X173600Y-73567D01*
X172433Y-73234D01*
X171267Y-73400D01*
X170267Y-73900D01*
X169600Y-75067D01*
X169267Y-76067D01*
Y-77067D01*
X169600Y-78067D01*
X170433Y-79067D01*
X171433Y-79733D01*
X172600Y-79900D01*
X173767Y-79567D01*
X174933Y-78567D01*
G01X183400Y-69900D02*
Y-79900D01*
G01X181067Y-73234D02*
X185733D01*
G01X192200Y-75400D02*
X197533D01*
X197033Y-74233D01*
X196200Y-73567D01*
X195033Y-73234D01*
X193867Y-73400D01*
X192867Y-73900D01*
X192200Y-75067D01*
X191867Y-76067D01*
Y-77067D01*
X192200Y-78067D01*
X193033Y-79067D01*
X194033Y-79733D01*
X195200Y-79900D01*
X196367Y-79567D01*
X197533Y-78567D01*
G01X203667Y-79900D02*
Y-73234D01*
G01Y-74567D02*
X204500Y-73900D01*
X205333Y-73400D01*
X206500Y-73234D01*
X207333Y-73400D01*
X208333Y-73900D01*
G01X14400Y56900D02*
X16733Y46900D01*
X19400Y56900D01*
X22067Y46900D01*
X24400Y56900D01*
G01X30700Y53566D02*
Y46900D01*
G01Y56233D02*
X30367Y56400D01*
Y56733D01*
X30700Y56900D01*
X31033Y56733D01*
Y56400D01*
X30700Y56233D01*
G01X39500Y48066D02*
X40333Y47400D01*
X41500Y46900D01*
X42500D01*
X43500Y47233D01*
X44167Y47733D01*
X44500Y48400D01*
X44333Y49400D01*
X43667Y49900D01*
X40666Y50900D01*
X40000Y52067D01*
X40333Y52900D01*
X41000Y53400D01*
X42000Y53566D01*
X43000Y53400D01*
X44000Y52900D01*
G01X53300Y56900D02*
Y46900D01*
G01X50967Y53566D02*
X55633D01*
G01X62267Y46900D02*
Y53566D01*
G01Y52233D02*
X63100Y52900D01*
X63933Y53400D01*
X65100Y53566D01*
X65933Y53400D01*
X66933Y52900D01*
G01X75900Y46900D02*
X74900Y47067D01*
X73900Y47733D01*
X73233Y48900D01*
X72900Y50233D01*
X73233Y51567D01*
X73900Y52733D01*
X74900Y53400D01*
X75900Y53566D01*
X76900Y53400D01*
X77900Y52733D01*
X78567Y51567D01*
X78733Y50233D01*
X78567Y48900D01*
X77900Y47733D01*
X76900Y47067D01*
X75900Y46900D01*
G01X84367D02*
Y53566D01*
G01Y51900D02*
X85033Y52733D01*
X86033Y53400D01*
X87367Y53566D01*
X88533Y53400D01*
X89533Y52733D01*
X90033Y51567D01*
Y46900D01*
G01X109800Y56900D02*
Y46900D01*
G01X105967Y56900D02*
X113633D01*
G01X117600Y46900D02*
Y56900D01*
G01X124600D02*
Y46900D01*
G01Y51900D02*
X117600D01*
G01X128067Y46900D02*
Y56900D01*
X132400Y48567D01*
X136733Y56900D01*
Y46900D01*
G01X140367Y56900D02*
Y46900D01*
X147033D01*
G01X169300Y56900D02*
Y46900D01*
G01Y48400D02*
X168633Y47567D01*
X167633Y47067D01*
X166467Y46900D01*
X165133Y47233D01*
X164133Y48066D01*
X163467Y49067D01*
X163300Y50233D01*
X163467Y51400D01*
X164133Y52400D01*
X165133Y53233D01*
X166467Y53566D01*
X167633Y53400D01*
X168467Y53067D01*
X169300Y52400D01*
G01X175100Y51400D02*
X180433D01*
X179933Y52567D01*
X179100Y53233D01*
X177933Y53566D01*
X176767Y53400D01*
X175767Y52900D01*
X175100Y51733D01*
X174767Y50733D01*
Y49733D01*
X175100Y48733D01*
X175933Y47733D01*
X176933Y47067D01*
X178100Y46900D01*
X179267Y47233D01*
X180433Y48233D01*
G01X187900Y46900D02*
Y55400D01*
X188233Y56233D01*
X188900Y56733D01*
X189900Y56900D01*
X190900Y56567D01*
X191400Y55733D01*
G01X189400Y52900D02*
X186067D01*
G01X203200Y46900D02*
Y53566D01*
G01Y52400D02*
X202533Y53067D01*
X201533Y53400D01*
X200367Y53566D01*
X199200Y53233D01*
X198200Y52567D01*
X197533Y51567D01*
X197200Y50233D01*
X197533Y48900D01*
X198200Y47900D01*
X199200Y47233D01*
X200367Y46900D01*
X201533Y47067D01*
X202533Y47567D01*
X203200Y48233D01*
G01X208667Y53566D02*
Y48900D01*
X209333Y47733D01*
X210333Y47067D01*
X211500Y46900D01*
X212667Y47067D01*
X213667Y47733D01*
X214333Y48900D01*
G01Y46900D02*
Y53566D01*
G01X222800Y46900D02*
Y56900D01*
G01X234100D02*
Y46900D01*
G01X231767Y53566D02*
X236433D01*
G01X256700Y56900D02*
Y46900D01*
G01X254367Y53566D02*
X259033D01*
G01X264500Y43900D02*
X265500Y43567D01*
X266833Y43900D01*
X267667Y44567D01*
X268333Y45400D01*
X269333Y48066D01*
X271500Y53566D01*
G01X266167D02*
X269333Y48066D01*
G01X276300Y43567D02*
Y53566D01*
G01Y52067D02*
X277133Y52900D01*
X277966Y53400D01*
X279300Y53566D01*
X280467Y53400D01*
X281633Y52567D01*
X282133Y51400D01*
X282300Y50233D01*
X282133Y49067D01*
X281633Y47900D01*
X280633Y47233D01*
X279300Y46900D01*
X278133Y47067D01*
X276967Y47567D01*
X276300Y48233D01*
G01X288100Y51400D02*
X293433D01*
X292933Y52567D01*
X292100Y53233D01*
X290933Y53566D01*
X289767Y53400D01*
X288767Y52900D01*
X288100Y51733D01*
X287767Y50733D01*
Y49733D01*
X288100Y48733D01*
X288933Y47733D01*
X289933Y47067D01*
X291100Y46900D01*
X292267Y47233D01*
X293433Y48233D01*
G01X95733Y-602100D02*
X89067D01*
Y-592100D01*
X95733D01*
G01X93067Y-596933D02*
X89067D01*
G01X101533Y-600267D02*
X105867D01*
G01Y-597267D02*
X101533D01*
G01X111333Y-600600D02*
X112333Y-601433D01*
X113500Y-601933D01*
X115000Y-602100D01*
X116500Y-601767D01*
X117667Y-601100D01*
X118500Y-599933D01*
X118667Y-598600D01*
X118333Y-597267D01*
X117500Y-596433D01*
X116333Y-595767D01*
X115167Y-595600D01*
X114000Y-595767D01*
X112500Y-596433D01*
X113000Y-592100D01*
X117500D01*
G01X133267Y-602100D02*
Y-592100D01*
X137600Y-600433D01*
X141933Y-592100D01*
Y-602100D01*
G01X146900Y-592100D02*
X150900D01*
G01X148900D02*
Y-602100D01*
G01X146900D02*
X150900D01*
G01X156867Y-592100D02*
Y-602100D01*
X163533D01*
G01X168000Y-600767D02*
X169333Y-601600D01*
X170833Y-602100D01*
X172167D01*
X173500Y-601600D01*
X174500Y-600767D01*
X175000Y-599600D01*
X174667Y-598434D01*
X173833Y-597433D01*
X172333Y-596767D01*
X170333Y-596433D01*
X169167Y-595767D01*
X168667Y-594600D01*
X169000Y-593433D01*
X169833Y-592600D01*
X171000Y-592100D01*
X172167D01*
X173333Y-592433D01*
X174333Y-593267D01*
G01X193267Y-605433D02*
X191600Y-603767D01*
X190767Y-602100D01*
Y-595434D01*
X191600Y-593767D01*
X193267Y-592100D01*
G01X208400Y-602100D02*
Y-595434D01*
G01Y-596600D02*
X207733Y-595933D01*
X206733Y-595600D01*
X205567Y-595434D01*
X204400Y-595767D01*
X203400Y-596433D01*
X202733Y-597433D01*
X202400Y-598767D01*
X202733Y-600100D01*
X203400Y-601100D01*
X204400Y-601767D01*
X205567Y-602100D01*
X206733Y-601933D01*
X207733Y-601433D01*
X208400Y-600767D01*
G01X216700Y-602100D02*
Y-592100D01*
G01X223833Y-595434D02*
X225833Y-602100D01*
X228000Y-595434D01*
X230167Y-602100D01*
X232167Y-595434D01*
G01X242300Y-602100D02*
Y-595434D01*
G01Y-596600D02*
X241633Y-595933D01*
X240633Y-595600D01*
X239467Y-595434D01*
X238300Y-595767D01*
X237300Y-596433D01*
X236633Y-597433D01*
X236300Y-598767D01*
X236633Y-600100D01*
X237300Y-601100D01*
X238300Y-601767D01*
X239467Y-602100D01*
X240633Y-601933D01*
X241633Y-601433D01*
X242300Y-600767D01*
G01X247100Y-605100D02*
X248100Y-605433D01*
X249433Y-605100D01*
X250267Y-604433D01*
X250933Y-603600D01*
X251933Y-600934D01*
X254100Y-595434D01*
G01X248767D02*
X251933Y-600934D01*
G01X259400D02*
X260233Y-601600D01*
X261400Y-602100D01*
X262400D01*
X263400Y-601767D01*
X264067Y-601267D01*
X264400Y-600600D01*
X264233Y-599600D01*
X263567Y-599100D01*
X260566Y-598100D01*
X259900Y-596933D01*
X260233Y-596100D01*
X260900Y-595600D01*
X261900Y-595434D01*
X262900Y-595600D01*
X263900Y-596100D01*
G01X281667Y-602100D02*
Y-592100D01*
G01X287000Y-595434D02*
X281667Y-599267D01*
G01X283833Y-597767D02*
X287333Y-602100D01*
G01X293300Y-597600D02*
X298633D01*
X298133Y-596433D01*
X297300Y-595767D01*
X296133Y-595434D01*
X294967Y-595600D01*
X293967Y-596100D01*
X293300Y-597267D01*
X292967Y-598267D01*
Y-599267D01*
X293300Y-600267D01*
X294133Y-601267D01*
X295133Y-601933D01*
X296300Y-602100D01*
X297467Y-601767D01*
X298633Y-600767D01*
G01X304600Y-597600D02*
X309933D01*
X309433Y-596433D01*
X308600Y-595767D01*
X307433Y-595434D01*
X306267Y-595600D01*
X305267Y-596100D01*
X304600Y-597267D01*
X304267Y-598267D01*
Y-599267D01*
X304600Y-600267D01*
X305433Y-601267D01*
X306433Y-601933D01*
X307600Y-602100D01*
X308767Y-601767D01*
X309933Y-600767D01*
G01X315400Y-605433D02*
Y-595434D01*
G01Y-596933D02*
X316233Y-596100D01*
X317066Y-595600D01*
X318400Y-595434D01*
X319567Y-595600D01*
X320733Y-596433D01*
X321233Y-597600D01*
X321400Y-598767D01*
X321233Y-599933D01*
X320733Y-601100D01*
X319733Y-601767D01*
X318400Y-602100D01*
X317233Y-601933D01*
X316067Y-601433D01*
X315400Y-600767D01*
G01X337333Y-600600D02*
X338333Y-601433D01*
X339500Y-601933D01*
X341000Y-602100D01*
X342500Y-601767D01*
X343667Y-601100D01*
X344500Y-599933D01*
X344667Y-598600D01*
X344333Y-597267D01*
X343500Y-596433D01*
X342333Y-595767D01*
X341167Y-595600D01*
X340000Y-595767D01*
X338500Y-596433D01*
X339000Y-592100D01*
X343500D01*
G01X358600Y-602100D02*
Y-595434D01*
G01Y-597267D02*
X359100Y-596433D01*
X359933Y-595767D01*
X361100Y-595434D01*
X362266Y-595767D01*
X363100Y-596433D01*
X363600Y-597267D01*
Y-602100D01*
G01Y-597267D02*
X364100Y-596433D01*
X364933Y-595767D01*
X366100Y-595434D01*
X367267Y-595767D01*
X368100Y-596433D01*
X368600Y-597433D01*
Y-602100D01*
G01X374900Y-595434D02*
Y-602100D01*
G01Y-592767D02*
X374567Y-592600D01*
Y-592267D01*
X374900Y-592100D01*
X375233Y-592267D01*
Y-592600D01*
X374900Y-592767D01*
G01X386200Y-602100D02*
Y-592100D01*
G01X395000Y-600934D02*
X395833Y-601600D01*
X397000Y-602100D01*
X398000D01*
X399000Y-601767D01*
X399667Y-601267D01*
X400000Y-600600D01*
X399833Y-599600D01*
X399167Y-599100D01*
X396166Y-598100D01*
X395500Y-596933D01*
X395833Y-596100D01*
X396500Y-595600D01*
X397500Y-595434D01*
X398500Y-595600D01*
X399500Y-596100D01*
G01X409633Y-605433D02*
X411300Y-603767D01*
X412133Y-602100D01*
Y-595434D01*
X411300Y-593767D01*
X409633Y-592100D01*
G01X128467Y-529733D02*
X127467Y-529233D01*
X126300Y-528900D01*
X124967D01*
X123466Y-529400D01*
X122300Y-530233D01*
X121467Y-531233D01*
X120800Y-532900D01*
X120633Y-534400D01*
X120967Y-535900D01*
X121467Y-536900D01*
X122467Y-537900D01*
X123633Y-538567D01*
X124800Y-538900D01*
X125967D01*
X127133Y-538567D01*
X128133Y-538067D01*
X128967Y-537400D01*
G01X120333Y-341300D02*
X124500Y-331300D01*
X128667Y-341300D01*
G01X127167Y-337800D02*
X121833D01*
G01X151890Y-22420D02*
X155223D01*
Y-25420D01*
X154223Y-26420D01*
X153057Y-27087D01*
X151390Y-27420D01*
X149723Y-27087D01*
X148557Y-26420D01*
X147557Y-25420D01*
X146890Y-24253D01*
X146557Y-22920D01*
Y-21753D01*
X146890Y-20754D01*
X147557Y-19587D01*
X148557Y-18587D01*
X149556Y-17920D01*
X150890Y-17420D01*
X152057D01*
X153390Y-17753D01*
X154390Y-18420D01*
G01X165190Y-27420D02*
Y-20754D01*
G01Y-21920D02*
X164523Y-21253D01*
X163523Y-20920D01*
X162357Y-20754D01*
X161190Y-21087D01*
X160190Y-21753D01*
X159523Y-22753D01*
X159190Y-24087D01*
X159523Y-25420D01*
X160190Y-26420D01*
X161190Y-27087D01*
X162357Y-27420D01*
X163523Y-27253D01*
X164523Y-26753D01*
X165190Y-26087D01*
G01X170490Y-30753D02*
Y-20754D01*
G01Y-22253D02*
X171323Y-21420D01*
X172156Y-20920D01*
X173490Y-20754D01*
X174657Y-20920D01*
X175823Y-21753D01*
X176323Y-22920D01*
X176490Y-24087D01*
X176323Y-25253D01*
X175823Y-26420D01*
X174823Y-27087D01*
X173490Y-27420D01*
X172323Y-27253D01*
X171157Y-26753D01*
X170490Y-26087D01*
G01X191090Y-17420D02*
X193423Y-27420D01*
X196090Y-17420D01*
X198757Y-27420D01*
X201090Y-17420D01*
G01X207390Y-20754D02*
Y-27420D01*
G01Y-18087D02*
X207057Y-17920D01*
Y-17587D01*
X207390Y-17420D01*
X207723Y-17587D01*
Y-17920D01*
X207390Y-18087D01*
G01X221690Y-17420D02*
Y-27420D01*
G01Y-25920D02*
X221023Y-26753D01*
X220023Y-27253D01*
X218857Y-27420D01*
X217523Y-27087D01*
X216523Y-26254D01*
X215857Y-25253D01*
X215690Y-24087D01*
X215857Y-22920D01*
X216523Y-21920D01*
X217523Y-21087D01*
X218857Y-20754D01*
X220023Y-20920D01*
X220857Y-21253D01*
X221690Y-21920D01*
G01X229990Y-17420D02*
Y-27420D01*
G01X227657Y-20754D02*
X232323D01*
G01X238457Y-27420D02*
Y-17420D01*
G01Y-22253D02*
X239290Y-21420D01*
X240123Y-20920D01*
X241457Y-20754D01*
X242457Y-20920D01*
X243623Y-21587D01*
X244123Y-22587D01*
Y-27420D01*
G01X154330Y21180D02*
X152996Y21347D01*
X151830Y22013D01*
X150830Y23013D01*
X150163Y24180D01*
X149830Y25513D01*
Y26847D01*
X150163Y28180D01*
X150830Y29347D01*
X151830Y30347D01*
X152996Y31013D01*
X154330Y31180D01*
X155663Y31013D01*
X156830Y30347D01*
X157830Y29347D01*
X158497Y28180D01*
X158830Y26847D01*
Y25513D01*
X158497Y24180D01*
X157830Y23013D01*
X156830Y22013D01*
X155663Y21347D01*
X154330Y21180D01*
G01X162797Y27846D02*
Y23180D01*
X163463Y22013D01*
X164463Y21347D01*
X165630Y21180D01*
X166797Y21347D01*
X167797Y22013D01*
X168463Y23180D01*
G01Y21180D02*
Y27846D01*
G01X176930Y31180D02*
Y21180D01*
G01X174597Y27846D02*
X179263D01*
G01X185730Y25680D02*
X191063D01*
X190563Y26847D01*
X189730Y27513D01*
X188563Y27846D01*
X187397Y27680D01*
X186397Y27180D01*
X185730Y26013D01*
X185397Y25013D01*
Y24013D01*
X185730Y23013D01*
X186563Y22013D01*
X187563Y21347D01*
X188730Y21180D01*
X189897Y21513D01*
X191063Y22513D01*
G01X197197Y21180D02*
Y27846D01*
G01Y26513D02*
X198030Y27180D01*
X198863Y27680D01*
X200030Y27846D01*
X200863Y27680D01*
X201863Y27180D01*
G01X218463Y21180D02*
Y31180D01*
X221797D01*
X223130Y30680D01*
X224130Y30013D01*
X224963Y29013D01*
X225630Y27846D01*
X225797Y26180D01*
X225630Y24513D01*
X224963Y23347D01*
X224130Y22346D01*
X223130Y21680D01*
X221797Y21180D01*
X218463D01*
G01X233430Y27846D02*
Y21180D01*
G01Y30513D02*
X233097Y30680D01*
Y31013D01*
X233430Y31180D01*
X233763Y31013D01*
Y30680D01*
X233430Y30513D01*
G01X247730Y21180D02*
Y27846D01*
G01Y26680D02*
X247063Y27347D01*
X246063Y27680D01*
X244897Y27846D01*
X243730Y27513D01*
X242730Y26847D01*
X242063Y25847D01*
X241730Y24513D01*
X242063Y23180D01*
X242730Y22180D01*
X243730Y21513D01*
X244897Y21180D01*
X246063Y21347D01*
X247063Y21847D01*
X247730Y22513D01*
G01X251030Y21180D02*
Y27846D01*
G01Y26013D02*
X251530Y26847D01*
X252363Y27513D01*
X253530Y27846D01*
X254696Y27513D01*
X255530Y26847D01*
X256030Y26013D01*
Y21180D01*
G01Y26013D02*
X256530Y26847D01*
X257363Y27513D01*
X258530Y27846D01*
X259697Y27513D01*
X260530Y26847D01*
X261030Y25847D01*
Y21180D01*
G01X264830Y25680D02*
X270163D01*
X269663Y26847D01*
X268830Y27513D01*
X267663Y27846D01*
X266497Y27680D01*
X265497Y27180D01*
X264830Y26013D01*
X264497Y25013D01*
Y24013D01*
X264830Y23013D01*
X265663Y22013D01*
X266663Y21347D01*
X267830Y21180D01*
X268997Y21513D01*
X270163Y22513D01*
G01X278630Y31180D02*
Y21180D01*
G01X276297Y27846D02*
X280963D01*
G01X287430Y25680D02*
X292763D01*
X292263Y26847D01*
X291430Y27513D01*
X290263Y27846D01*
X289097Y27680D01*
X288097Y27180D01*
X287430Y26013D01*
X287097Y25013D01*
Y24013D01*
X287430Y23013D01*
X288263Y22013D01*
X289263Y21347D01*
X290430Y21180D01*
X291597Y21513D01*
X292763Y22513D01*
G01X298897Y21180D02*
Y27846D01*
G01Y26513D02*
X299730Y27180D01*
X300563Y27680D01*
X301730Y27846D01*
X302563Y27680D01*
X303563Y27180D01*
G01X193433Y-427567D02*
X194100Y-427067D01*
X194600Y-426234D01*
X194933Y-425067D01*
X194600Y-424067D01*
X193933Y-423400D01*
X192767Y-422900D01*
X188267D01*
Y-432900D01*
X193767D01*
X194933Y-432233D01*
X195600Y-431233D01*
X195933Y-430067D01*
X195600Y-428900D01*
X194600Y-427900D01*
X193433Y-427567D01*
X188267D01*
G01X221400Y-131100D02*
X220066Y-130933D01*
X218900Y-130267D01*
X217900Y-129267D01*
X217233Y-128100D01*
X216900Y-126767D01*
Y-125433D01*
X217233Y-124100D01*
X217900Y-122933D01*
X218900Y-121933D01*
X220066Y-121267D01*
X221400Y-121100D01*
X222733Y-121267D01*
X223900Y-121933D01*
X224900Y-122933D01*
X225567Y-124100D01*
X225900Y-125433D01*
Y-126767D01*
X225567Y-128100D01*
X224900Y-129267D01*
X223900Y-130267D01*
X222733Y-130933D01*
X221400Y-131100D01*
G01X229867Y-124434D02*
Y-129100D01*
X230533Y-130267D01*
X231533Y-130933D01*
X232700Y-131100D01*
X233867Y-130933D01*
X234867Y-130267D01*
X235533Y-129100D01*
G01Y-131100D02*
Y-124434D01*
G01X244000Y-121100D02*
Y-131100D01*
G01X241667Y-124434D02*
X246333D01*
G01X252800Y-126600D02*
X258133D01*
X257633Y-125433D01*
X256800Y-124767D01*
X255633Y-124434D01*
X254467Y-124600D01*
X253467Y-125100D01*
X252800Y-126267D01*
X252467Y-127267D01*
Y-128267D01*
X252800Y-129267D01*
X253633Y-130267D01*
X254633Y-130933D01*
X255800Y-131100D01*
X256967Y-130767D01*
X258133Y-129767D01*
G01X264267Y-131100D02*
Y-124434D01*
G01Y-125767D02*
X265100Y-125100D01*
X265933Y-124600D01*
X267100Y-124434D01*
X267933Y-124600D01*
X268933Y-125100D01*
G01X285533Y-131100D02*
Y-121100D01*
X288867D01*
X290200Y-121600D01*
X291200Y-122267D01*
X292033Y-123267D01*
X292700Y-124434D01*
X292867Y-126100D01*
X292700Y-127767D01*
X292033Y-128933D01*
X291200Y-129934D01*
X290200Y-130600D01*
X288867Y-131100D01*
X285533D01*
G01X300500Y-124434D02*
Y-131100D01*
G01Y-121767D02*
X300167Y-121600D01*
Y-121267D01*
X300500Y-121100D01*
X300833Y-121267D01*
Y-121600D01*
X300500Y-121767D01*
G01X314800Y-131100D02*
Y-124434D01*
G01Y-125600D02*
X314133Y-124933D01*
X313133Y-124600D01*
X311967Y-124434D01*
X310800Y-124767D01*
X309800Y-125433D01*
X309133Y-126433D01*
X308800Y-127767D01*
X309133Y-129100D01*
X309800Y-130100D01*
X310800Y-130767D01*
X311967Y-131100D01*
X313133Y-130933D01*
X314133Y-130433D01*
X314800Y-129767D01*
G01X318100Y-131100D02*
Y-124434D01*
G01Y-126267D02*
X318600Y-125433D01*
X319433Y-124767D01*
X320600Y-124434D01*
X321766Y-124767D01*
X322600Y-125433D01*
X323100Y-126267D01*
Y-131100D01*
G01Y-126267D02*
X323600Y-125433D01*
X324433Y-124767D01*
X325600Y-124434D01*
X326767Y-124767D01*
X327600Y-125433D01*
X328100Y-126433D01*
Y-131100D01*
G01X331900Y-126600D02*
X337233D01*
X336733Y-125433D01*
X335900Y-124767D01*
X334733Y-124434D01*
X333567Y-124600D01*
X332567Y-125100D01*
X331900Y-126267D01*
X331567Y-127267D01*
Y-128267D01*
X331900Y-129267D01*
X332733Y-130267D01*
X333733Y-130933D01*
X334900Y-131100D01*
X336067Y-130767D01*
X337233Y-129767D01*
G01X345700Y-121100D02*
Y-131100D01*
G01X343367Y-124434D02*
X348033D01*
G01X354500Y-126600D02*
X359833D01*
X359333Y-125433D01*
X358500Y-124767D01*
X357333Y-124434D01*
X356167Y-124600D01*
X355167Y-125100D01*
X354500Y-126267D01*
X354167Y-127267D01*
Y-128267D01*
X354500Y-129267D01*
X355333Y-130267D01*
X356333Y-130933D01*
X357500Y-131100D01*
X358667Y-130767D01*
X359833Y-129767D01*
G01X365967Y-131100D02*
Y-124434D01*
G01Y-125767D02*
X366800Y-125100D01*
X367633Y-124600D01*
X368800Y-124434D01*
X369633Y-124600D01*
X370633Y-125100D01*
G01X377433Y-129267D02*
X381767D01*
G01Y-126267D02*
X377433D01*
G01X390900Y-131100D02*
Y-121100D01*
X388900Y-123100D01*
G01Y-131100D02*
X392900D01*
G01X402200Y-121100D02*
X400866Y-121433D01*
X399867Y-122267D01*
X399200Y-123267D01*
X398700Y-124600D01*
X398533Y-126100D01*
X398700Y-127600D01*
X399200Y-128933D01*
X399867Y-129934D01*
X400866Y-130767D01*
X402200Y-131100D01*
X403533Y-130767D01*
X404533Y-129934D01*
X405200Y-128933D01*
X405700Y-127600D01*
X405867Y-126100D01*
X405700Y-124600D01*
X405200Y-123267D01*
X404533Y-122267D01*
X403533Y-121433D01*
X402200Y-121100D01*
G01X409833Y-129100D02*
X410833Y-130267D01*
X412166Y-130933D01*
X413667Y-131100D01*
X415000Y-130933D01*
X416333Y-130100D01*
X417167Y-129100D01*
X417333Y-128100D01*
X417000Y-126934D01*
X415833Y-126100D01*
X414667Y-125767D01*
X413167D01*
G01X414667D02*
X415667Y-125267D01*
X416500Y-124434D01*
X416833Y-123433D01*
X416500Y-122433D01*
X415667Y-121600D01*
X414167Y-121100D01*
X412667Y-121267D01*
X411167Y-121933D01*
G01X222400Y-162100D02*
X225733D01*
Y-165100D01*
X224733Y-166100D01*
X223567Y-166767D01*
X221900Y-167100D01*
X220233Y-166767D01*
X219067Y-166100D01*
X218067Y-165100D01*
X217400Y-163933D01*
X217067Y-162600D01*
Y-161433D01*
X217400Y-160434D01*
X218067Y-159267D01*
X219067Y-158267D01*
X220066Y-157600D01*
X221400Y-157100D01*
X222567D01*
X223900Y-157433D01*
X224900Y-158100D01*
G01X235700Y-167100D02*
Y-160434D01*
G01Y-161600D02*
X235033Y-160933D01*
X234033Y-160600D01*
X232867Y-160434D01*
X231700Y-160767D01*
X230700Y-161433D01*
X230033Y-162433D01*
X229700Y-163767D01*
X230033Y-165100D01*
X230700Y-166100D01*
X231700Y-166767D01*
X232867Y-167100D01*
X234033Y-166933D01*
X235033Y-166433D01*
X235700Y-165767D01*
G01X241000Y-170433D02*
Y-160434D01*
G01Y-161933D02*
X241833Y-161100D01*
X242666Y-160600D01*
X244000Y-160434D01*
X245167Y-160600D01*
X246333Y-161433D01*
X246833Y-162600D01*
X247000Y-163767D01*
X246833Y-164933D01*
X246333Y-166100D01*
X245333Y-166767D01*
X244000Y-167100D01*
X242833Y-166933D01*
X241667Y-166433D01*
X241000Y-165767D01*
G01X261600Y-157100D02*
X263933Y-167100D01*
X266600Y-157100D01*
X269267Y-167100D01*
X271600Y-157100D01*
G01X277900Y-160434D02*
Y-167100D01*
G01Y-157767D02*
X277567Y-157600D01*
Y-157267D01*
X277900Y-157100D01*
X278233Y-157267D01*
Y-157600D01*
X277900Y-157767D01*
G01X292200Y-157100D02*
Y-167100D01*
G01Y-165600D02*
X291533Y-166433D01*
X290533Y-166933D01*
X289367Y-167100D01*
X288033Y-166767D01*
X287033Y-165934D01*
X286367Y-164933D01*
X286200Y-163767D01*
X286367Y-162600D01*
X287033Y-161600D01*
X288033Y-160767D01*
X289367Y-160434D01*
X290533Y-160600D01*
X291367Y-160933D01*
X292200Y-161600D01*
G01X300500Y-157100D02*
Y-167100D01*
G01X298167Y-160434D02*
X302833D01*
G01X308967Y-167100D02*
Y-157100D01*
G01Y-161933D02*
X309800Y-161100D01*
X310633Y-160600D01*
X311967Y-160434D01*
X312967Y-160600D01*
X314133Y-161267D01*
X314633Y-162267D01*
Y-167100D01*
G01X320933Y-165267D02*
X325267D01*
G01Y-162267D02*
X320933D01*
G01X330733Y-165100D02*
X331733Y-166267D01*
X333066Y-166933D01*
X334567Y-167100D01*
X335900Y-166933D01*
X337233Y-166100D01*
X338067Y-165100D01*
X338233Y-164100D01*
X337900Y-162934D01*
X336733Y-162100D01*
X335567Y-161767D01*
X334067D01*
G01X335567D02*
X336567Y-161267D01*
X337400Y-160434D01*
X337733Y-159433D01*
X337400Y-158433D01*
X336567Y-157600D01*
X335067Y-157100D01*
X333567Y-157267D01*
X332067Y-157933D01*
G01X345700Y-157100D02*
X344366Y-157433D01*
X343367Y-158267D01*
X342700Y-159267D01*
X342200Y-160600D01*
X342033Y-162100D01*
X342200Y-163600D01*
X342700Y-164933D01*
X343367Y-165934D01*
X344366Y-166767D01*
X345700Y-167100D01*
X347033Y-166767D01*
X348033Y-165934D01*
X348700Y-164933D01*
X349200Y-163600D01*
X349367Y-162100D01*
X349200Y-160600D01*
X348700Y-159267D01*
X348033Y-158267D01*
X347033Y-157433D01*
X345700Y-157100D01*
G01X219567Y-151100D02*
Y-141100D01*
X227233Y-151100D01*
Y-141100D01*
G01X231867Y-144434D02*
Y-149100D01*
X232533Y-150267D01*
X233533Y-150933D01*
X234700Y-151100D01*
X235867Y-150933D01*
X236867Y-150267D01*
X237533Y-149100D01*
G01Y-151100D02*
Y-144434D01*
G01X241000Y-151100D02*
Y-144434D01*
G01Y-146267D02*
X241500Y-145433D01*
X242333Y-144767D01*
X243500Y-144434D01*
X244666Y-144767D01*
X245500Y-145433D01*
X246000Y-146267D01*
Y-151100D01*
G01Y-146267D02*
X246500Y-145433D01*
X247333Y-144767D01*
X248500Y-144434D01*
X249667Y-144767D01*
X250500Y-145433D01*
X251000Y-146433D01*
Y-151100D01*
G01X265100Y-149767D02*
X266433Y-150600D01*
X267933Y-151100D01*
X269267D01*
X270600Y-150600D01*
X271600Y-149767D01*
X272100Y-148600D01*
X271767Y-147434D01*
X270933Y-146433D01*
X269433Y-145767D01*
X267433Y-145433D01*
X266267Y-144767D01*
X265767Y-143600D01*
X266100Y-142433D01*
X266933Y-141600D01*
X268100Y-141100D01*
X269267D01*
X270433Y-141433D01*
X271433Y-142267D01*
G01X276900Y-154433D02*
Y-144434D01*
G01Y-145933D02*
X277733Y-145100D01*
X278566Y-144600D01*
X279900Y-144434D01*
X281067Y-144600D01*
X282233Y-145433D01*
X282733Y-146600D01*
X282900Y-147767D01*
X282733Y-148933D01*
X282233Y-150100D01*
X281233Y-150767D01*
X279900Y-151100D01*
X278733Y-150933D01*
X277567Y-150433D01*
X276900Y-149767D01*
G01X291200Y-151100D02*
X290200Y-150933D01*
X289200Y-150267D01*
X288533Y-149100D01*
X288200Y-147767D01*
X288533Y-146433D01*
X289200Y-145267D01*
X290200Y-144600D01*
X291200Y-144434D01*
X292200Y-144600D01*
X293200Y-145267D01*
X293867Y-146433D01*
X294033Y-147767D01*
X293867Y-149100D01*
X293200Y-150267D01*
X292200Y-150933D01*
X291200Y-151100D01*
G01X299667D02*
Y-141100D01*
G01X305000Y-144434D02*
X299667Y-148267D01*
G01X301833Y-146767D02*
X305333Y-151100D01*
G01X311300Y-146600D02*
X316633D01*
X316133Y-145433D01*
X315300Y-144767D01*
X314133Y-144434D01*
X312967Y-144600D01*
X311967Y-145100D01*
X311300Y-146267D01*
X310967Y-147267D01*
Y-148267D01*
X311300Y-149267D01*
X312133Y-150267D01*
X313133Y-150933D01*
X314300Y-151100D01*
X315467Y-150767D01*
X316633Y-149767D01*
G01X322600Y-149934D02*
X323433Y-150600D01*
X324600Y-151100D01*
X325600D01*
X326600Y-150767D01*
X327267Y-150267D01*
X327600Y-149600D01*
X327433Y-148600D01*
X326767Y-148100D01*
X323766Y-147100D01*
X323100Y-145933D01*
X323433Y-145100D01*
X324100Y-144600D01*
X325100Y-144434D01*
X326100Y-144600D01*
X327100Y-145100D01*
G01X334233Y-149267D02*
X338567D01*
G01Y-146267D02*
X334233D01*
G01X349700Y-151100D02*
Y-141100D01*
X343533Y-148267D01*
X351867D01*
G01X217400Y-99100D02*
X221400D01*
G01X219400D02*
Y-109100D01*
G01X217400D02*
X221400D01*
G01X227867D02*
Y-102434D01*
G01Y-104100D02*
X228533Y-103267D01*
X229533Y-102600D01*
X230867Y-102434D01*
X232033Y-102600D01*
X233033Y-103267D01*
X233533Y-104433D01*
Y-109100D01*
G01X239167D02*
Y-102434D01*
G01Y-104100D02*
X239833Y-103267D01*
X240833Y-102600D01*
X242167Y-102434D01*
X243333Y-102600D01*
X244333Y-103267D01*
X244833Y-104433D01*
Y-109100D01*
G01X250800Y-104600D02*
X256133D01*
X255633Y-103433D01*
X254800Y-102767D01*
X253633Y-102434D01*
X252467Y-102600D01*
X251467Y-103100D01*
X250800Y-104267D01*
X250467Y-105267D01*
Y-106267D01*
X250800Y-107267D01*
X251633Y-108267D01*
X252633Y-108933D01*
X253800Y-109100D01*
X254967Y-108767D01*
X256133Y-107767D01*
G01X262267Y-109100D02*
Y-102434D01*
G01Y-103767D02*
X263100Y-103100D01*
X263933Y-102600D01*
X265100Y-102434D01*
X265933Y-102600D01*
X266933Y-103100D01*
G01X283533Y-109100D02*
Y-99100D01*
X286867D01*
X288200Y-99600D01*
X289200Y-100267D01*
X290033Y-101267D01*
X290700Y-102434D01*
X290867Y-104100D01*
X290700Y-105767D01*
X290033Y-106933D01*
X289200Y-107934D01*
X288200Y-108600D01*
X286867Y-109100D01*
X283533D01*
G01X298500Y-102434D02*
Y-109100D01*
G01Y-99767D02*
X298167Y-99600D01*
Y-99267D01*
X298500Y-99100D01*
X298833Y-99267D01*
Y-99600D01*
X298500Y-99767D01*
G01X312800Y-109100D02*
Y-102434D01*
G01Y-103600D02*
X312133Y-102933D01*
X311133Y-102600D01*
X309967Y-102434D01*
X308800Y-102767D01*
X307800Y-103433D01*
X307133Y-104433D01*
X306800Y-105767D01*
X307133Y-107100D01*
X307800Y-108100D01*
X308800Y-108767D01*
X309967Y-109100D01*
X311133Y-108933D01*
X312133Y-108433D01*
X312800Y-107767D01*
G01X316100Y-109100D02*
Y-102434D01*
G01Y-104267D02*
X316600Y-103433D01*
X317433Y-102767D01*
X318600Y-102434D01*
X319766Y-102767D01*
X320600Y-103433D01*
X321100Y-104267D01*
Y-109100D01*
G01Y-104267D02*
X321600Y-103433D01*
X322433Y-102767D01*
X323600Y-102434D01*
X324767Y-102767D01*
X325600Y-103433D01*
X326100Y-104433D01*
Y-109100D01*
G01X329900Y-104600D02*
X335233D01*
X334733Y-103433D01*
X333900Y-102767D01*
X332733Y-102434D01*
X331567Y-102600D01*
X330567Y-103100D01*
X329900Y-104267D01*
X329567Y-105267D01*
Y-106267D01*
X329900Y-107267D01*
X330733Y-108267D01*
X331733Y-108933D01*
X332900Y-109100D01*
X334067Y-108767D01*
X335233Y-107767D01*
G01X343700Y-99100D02*
Y-109100D01*
G01X341367Y-102434D02*
X346033D01*
G01X352500Y-104600D02*
X357833D01*
X357333Y-103433D01*
X356500Y-102767D01*
X355333Y-102434D01*
X354167Y-102600D01*
X353167Y-103100D01*
X352500Y-104267D01*
X352167Y-105267D01*
Y-106267D01*
X352500Y-107267D01*
X353333Y-108267D01*
X354333Y-108933D01*
X355500Y-109100D01*
X356667Y-108767D01*
X357833Y-107767D01*
G01X363967Y-109100D02*
Y-102434D01*
G01Y-103767D02*
X364800Y-103100D01*
X365633Y-102600D01*
X366800Y-102434D01*
X367633Y-102600D01*
X368633Y-103100D01*
G01X375433Y-107267D02*
X379767D01*
G01Y-104267D02*
X375433D01*
G01X386067Y-107934D02*
X387233Y-108767D01*
X388567Y-109100D01*
X389900Y-108767D01*
X391067Y-107767D01*
X391900Y-106267D01*
X392233Y-104767D01*
Y-102933D01*
X391900Y-101433D01*
X391067Y-100100D01*
X390067Y-99433D01*
X388900Y-99100D01*
X387566Y-99433D01*
X386567Y-100100D01*
X385900Y-101100D01*
X385567Y-102434D01*
X385900Y-103600D01*
X386733Y-104767D01*
X387733Y-105434D01*
X388900Y-105600D01*
X390233Y-105267D01*
X391233Y-104433D01*
X392233Y-102933D01*
G01X396533Y-107100D02*
X397533Y-108267D01*
X398866Y-108933D01*
X400367Y-109100D01*
X401700Y-108933D01*
X403033Y-108100D01*
X403867Y-107100D01*
X404033Y-106100D01*
X403700Y-104934D01*
X402533Y-104100D01*
X401367Y-103767D01*
X399867D01*
G01X401367D02*
X402367Y-103267D01*
X403200Y-102434D01*
X403533Y-101433D01*
X403200Y-100433D01*
X402367Y-99600D01*
X400867Y-99100D01*
X399367Y-99267D01*
X397867Y-99933D01*
G54D12*
G01X530200Y-653000D02*
Y-645000D01*
X534000D01*
G01X532600Y-648867D02*
X530200D01*
G01X540100Y-653000D02*
X539500Y-652867D01*
X538900Y-652333D01*
X538500Y-651400D01*
X538300Y-650333D01*
X538500Y-649267D01*
X538900Y-648333D01*
X539500Y-647800D01*
X540100Y-647667D01*
X540700Y-647800D01*
X541300Y-648333D01*
X541700Y-649267D01*
X541800Y-650333D01*
X541700Y-651400D01*
X541300Y-652333D01*
X540700Y-652867D01*
X540100Y-653000D01*
G01X546700D02*
Y-647667D01*
G01Y-648733D02*
X547200Y-648200D01*
X547700Y-647800D01*
X548400Y-647667D01*
X548900Y-647800D01*
X549500Y-648200D01*
G01X562600Y-649400D02*
X565800D01*
X565500Y-648467D01*
X565000Y-647933D01*
X564300Y-647667D01*
X563600Y-647800D01*
X563000Y-648200D01*
X562600Y-649133D01*
X562400Y-649934D01*
Y-650733D01*
X562600Y-651533D01*
X563100Y-652333D01*
X563700Y-652867D01*
X564400Y-653000D01*
X565100Y-652733D01*
X565800Y-651934D01*
G01X570600Y-647667D02*
X573600Y-653000D01*
G01Y-647667D02*
X570600Y-653000D01*
G01X581900D02*
Y-647667D01*
G01Y-648600D02*
X581500Y-648067D01*
X580900Y-647800D01*
X580200Y-647667D01*
X579500Y-647933D01*
X578900Y-648467D01*
X578500Y-649267D01*
X578300Y-650333D01*
X578500Y-651400D01*
X578900Y-652200D01*
X579500Y-652733D01*
X580200Y-653000D01*
X580900Y-652867D01*
X581500Y-652467D01*
X581900Y-651934D01*
G01X585100Y-653000D02*
Y-647667D01*
G01Y-649133D02*
X585400Y-648467D01*
X585900Y-647933D01*
X586600Y-647667D01*
X587300Y-647933D01*
X587800Y-648467D01*
X588100Y-649133D01*
Y-653000D01*
G01Y-649133D02*
X588400Y-648467D01*
X588900Y-647933D01*
X589600Y-647667D01*
X590300Y-647933D01*
X590800Y-648467D01*
X591100Y-649267D01*
Y-653000D01*
G01X594300Y-655667D02*
Y-647667D01*
G01Y-648867D02*
X594800Y-648200D01*
X595300Y-647800D01*
X596100Y-647667D01*
X596800Y-647800D01*
X597500Y-648467D01*
X597800Y-649400D01*
X597900Y-650333D01*
X597800Y-651267D01*
X597500Y-652200D01*
X596900Y-652733D01*
X596100Y-653000D01*
X595400Y-652867D01*
X594700Y-652467D01*
X594300Y-651934D01*
G01X604100Y-653000D02*
Y-645000D01*
G01X610600Y-649400D02*
X613800D01*
X613500Y-648467D01*
X613000Y-647933D01*
X612300Y-647667D01*
X611600Y-647800D01*
X611000Y-648200D01*
X610600Y-649133D01*
X610400Y-649934D01*
Y-650733D01*
X610600Y-651533D01*
X611100Y-652333D01*
X611700Y-652867D01*
X612400Y-653000D01*
X613100Y-652733D01*
X613800Y-651934D01*
G01X620100Y-653267D02*
X619900Y-653133D01*
Y-652867D01*
X620100Y-652733D01*
X620300Y-652867D01*
Y-653133D01*
X620100Y-653267D01*
G01Y-649667D02*
X619900Y-649533D01*
Y-649267D01*
X620100Y-649133D01*
X620300Y-649267D01*
Y-649533D01*
X620100Y-649667D01*
G01X634000Y-653000D02*
Y-645000D01*
G01X638200D02*
Y-653000D01*
G01Y-649000D02*
X634000D01*
G01X644100Y-653000D02*
X643500Y-652867D01*
X642900Y-652333D01*
X642500Y-651400D01*
X642300Y-650333D01*
X642500Y-649267D01*
X642900Y-648333D01*
X643500Y-647800D01*
X644100Y-647667D01*
X644700Y-647800D01*
X645300Y-648333D01*
X645700Y-649267D01*
X645800Y-650333D01*
X645700Y-651400D01*
X645300Y-652333D01*
X644700Y-652867D01*
X644100Y-653000D01*
G01X652100D02*
Y-645000D01*
G01X658600Y-649400D02*
X661800D01*
X661500Y-648467D01*
X661000Y-647933D01*
X660300Y-647667D01*
X659600Y-647800D01*
X659000Y-648200D01*
X658600Y-649133D01*
X658400Y-649934D01*
Y-650733D01*
X658600Y-651533D01*
X659100Y-652333D01*
X659700Y-652867D01*
X660400Y-653000D01*
X661100Y-652733D01*
X661800Y-651934D01*
G01X673900Y-653000D02*
Y-645000D01*
X675900D01*
X676700Y-645400D01*
X677300Y-645933D01*
X677800Y-646733D01*
X678200Y-647667D01*
X678300Y-649000D01*
X678200Y-650333D01*
X677800Y-651267D01*
X677300Y-652067D01*
X676700Y-652600D01*
X675900Y-653000D01*
X673900D01*
G01X684100Y-647667D02*
Y-653000D01*
G01Y-645533D02*
X683900Y-645400D01*
Y-645133D01*
X684100Y-645000D01*
X684300Y-645133D01*
Y-645400D01*
X684100Y-645533D01*
G01X693900Y-653000D02*
Y-647667D01*
G01Y-648600D02*
X693500Y-648067D01*
X692900Y-647800D01*
X692200Y-647667D01*
X691500Y-647933D01*
X690900Y-648467D01*
X690500Y-649267D01*
X690300Y-650333D01*
X690500Y-651400D01*
X690900Y-652200D01*
X691500Y-652733D01*
X692200Y-653000D01*
X692900Y-652867D01*
X693500Y-652467D01*
X693900Y-651934D01*
G01X700100Y-653267D02*
X699900Y-653133D01*
Y-652867D01*
X700100Y-652733D01*
X700300Y-652867D01*
Y-653133D01*
X700100Y-653267D01*
G01X705900Y-651400D02*
X706500Y-652333D01*
X707300Y-652867D01*
X708200Y-653000D01*
X709000Y-652867D01*
X709800Y-652200D01*
X710300Y-651400D01*
X710400Y-650600D01*
X710200Y-649667D01*
X709500Y-649000D01*
X708800Y-648733D01*
X707900D01*
G01X708800D02*
X709400Y-648333D01*
X709900Y-647667D01*
X710100Y-646867D01*
X709900Y-646067D01*
X709400Y-645400D01*
X708500Y-645000D01*
X707600Y-645133D01*
X706700Y-645667D01*
G01X716100Y-653267D02*
X715900Y-653133D01*
Y-652867D01*
X716100Y-652733D01*
X716300Y-652867D01*
Y-653133D01*
X716100Y-653267D01*
G01X724100Y-653000D02*
Y-645000D01*
X722900Y-646600D01*
G01Y-653000D02*
X725300D01*
G01X732100D02*
X732800Y-652867D01*
X733600Y-652467D01*
X734100Y-651800D01*
X734300Y-650867D01*
X734100Y-649934D01*
X733500Y-649133D01*
X732600Y-648733D01*
X731600D01*
X731000Y-648467D01*
X730500Y-647800D01*
X730300Y-646867D01*
X730600Y-645933D01*
X731300Y-645267D01*
X732100Y-645000D01*
X732900Y-645267D01*
X733600Y-645933D01*
X733900Y-646867D01*
X733700Y-647800D01*
X733200Y-648467D01*
X732600Y-648733D01*
X731600D01*
X730700Y-649133D01*
X730100Y-649934D01*
X729900Y-650867D01*
X730100Y-651800D01*
X730600Y-652467D01*
X731400Y-652867D01*
X732100Y-653000D01*
G01X737100D02*
Y-647667D01*
G01Y-649133D02*
X737400Y-648467D01*
X737900Y-647933D01*
X738600Y-647667D01*
X739300Y-647933D01*
X739800Y-648467D01*
X740100Y-649133D01*
Y-653000D01*
G01Y-649133D02*
X740400Y-648467D01*
X740900Y-647933D01*
X741600Y-647667D01*
X742300Y-647933D01*
X742800Y-648467D01*
X743100Y-649267D01*
Y-653000D01*
G01X745100D02*
Y-647667D01*
G01Y-649133D02*
X745400Y-648467D01*
X745900Y-647933D01*
X746600Y-647667D01*
X747300Y-647933D01*
X747800Y-648467D01*
X748100Y-649133D01*
Y-653000D01*
G01Y-649133D02*
X748400Y-648467D01*
X748900Y-647933D01*
X749600Y-647667D01*
X750300Y-647933D01*
X750800Y-648467D01*
X751100Y-649267D01*
Y-653000D01*
G01X764100Y-647667D02*
Y-653000D01*
G01Y-645533D02*
X763900Y-645400D01*
Y-645133D01*
X764100Y-645000D01*
X764300Y-645133D01*
Y-645400D01*
X764100Y-645533D01*
G01X770600Y-652067D02*
X771100Y-652600D01*
X771800Y-653000D01*
X772400D01*
X773000Y-652733D01*
X773400Y-652333D01*
X773600Y-651800D01*
X773500Y-651000D01*
X773100Y-650600D01*
X771300Y-649800D01*
X770900Y-648867D01*
X771100Y-648200D01*
X771500Y-647800D01*
X772100Y-647667D01*
X772700Y-647800D01*
X773300Y-648200D01*
G01X785100Y-653000D02*
Y-647667D01*
G01Y-649133D02*
X785400Y-648467D01*
X785900Y-647933D01*
X786600Y-647667D01*
X787300Y-647933D01*
X787800Y-648467D01*
X788100Y-649133D01*
Y-653000D01*
G01Y-649133D02*
X788400Y-648467D01*
X788900Y-647933D01*
X789600Y-647667D01*
X790300Y-647933D01*
X790800Y-648467D01*
X791100Y-649267D01*
Y-653000D01*
G01X797900D02*
Y-647667D01*
G01Y-648600D02*
X797500Y-648067D01*
X796900Y-647800D01*
X796200Y-647667D01*
X795500Y-647933D01*
X794900Y-648467D01*
X794500Y-649267D01*
X794300Y-650333D01*
X794500Y-651400D01*
X794900Y-652200D01*
X795500Y-652733D01*
X796200Y-653000D01*
X796900Y-652867D01*
X797500Y-652467D01*
X797900Y-651934D01*
G01X802700Y-653000D02*
Y-647667D01*
G01Y-648733D02*
X803200Y-648200D01*
X803700Y-647800D01*
X804400Y-647667D01*
X804900Y-647800D01*
X805500Y-648200D01*
G01X810400Y-653000D02*
Y-645000D01*
G01X813600Y-647667D02*
X810400Y-650733D01*
G01X811700Y-649533D02*
X813800Y-653000D01*
G01X818600Y-649400D02*
X821800D01*
X821500Y-648467D01*
X821000Y-647933D01*
X820300Y-647667D01*
X819600Y-647800D01*
X819000Y-648200D01*
X818600Y-649133D01*
X818400Y-649934D01*
Y-650733D01*
X818600Y-651533D01*
X819100Y-652333D01*
X819700Y-652867D01*
X820400Y-653000D01*
X821100Y-652733D01*
X821800Y-651934D01*
G01X829900Y-645000D02*
Y-653000D01*
G01Y-651800D02*
X829500Y-652467D01*
X828900Y-652867D01*
X828200Y-653000D01*
X827400Y-652733D01*
X826800Y-652067D01*
X826400Y-651267D01*
X826300Y-650333D01*
X826400Y-649400D01*
X826800Y-648600D01*
X827400Y-647933D01*
X828200Y-647667D01*
X828900Y-647800D01*
X829400Y-648067D01*
X829900Y-648600D01*
G01X844100Y-647667D02*
Y-653000D01*
G01Y-645533D02*
X843900Y-645400D01*
Y-645133D01*
X844100Y-645000D01*
X844300Y-645133D01*
Y-645400D01*
X844100Y-645533D01*
G01X850400Y-653000D02*
Y-647667D01*
G01Y-649000D02*
X850800Y-648333D01*
X851400Y-647800D01*
X852200Y-647667D01*
X852900Y-647800D01*
X853500Y-648333D01*
X853800Y-649267D01*
Y-653000D01*
G01X865100D02*
Y-647667D01*
G01Y-649133D02*
X865400Y-648467D01*
X865900Y-647933D01*
X866600Y-647667D01*
X867300Y-647933D01*
X867800Y-648467D01*
X868100Y-649133D01*
Y-653000D01*
G01Y-649133D02*
X868400Y-648467D01*
X868900Y-647933D01*
X869600Y-647667D01*
X870300Y-647933D01*
X870800Y-648467D01*
X871100Y-649267D01*
Y-653000D01*
G01X874600Y-649400D02*
X877800D01*
X877500Y-648467D01*
X877000Y-647933D01*
X876300Y-647667D01*
X875600Y-647800D01*
X875000Y-648200D01*
X874600Y-649133D01*
X874400Y-649934D01*
Y-650733D01*
X874600Y-651533D01*
X875100Y-652333D01*
X875700Y-652867D01*
X876400Y-653000D01*
X877100Y-652733D01*
X877800Y-651934D01*
G01X885700Y-648333D02*
X885000Y-647800D01*
X884400Y-647667D01*
X883600Y-647933D01*
X883000Y-648467D01*
X882600Y-649400D01*
X882500Y-650333D01*
X882600Y-651267D01*
X883000Y-652067D01*
X883600Y-652733D01*
X884400Y-653000D01*
X885100Y-652733D01*
X885700Y-652200D01*
G01X890400Y-653000D02*
Y-645000D01*
G01Y-648867D02*
X890900Y-648200D01*
X891400Y-647800D01*
X892200Y-647667D01*
X892800Y-647800D01*
X893500Y-648333D01*
X893800Y-649133D01*
Y-653000D01*
G01X901900D02*
Y-647667D01*
G01Y-648600D02*
X901500Y-648067D01*
X900900Y-647800D01*
X900200Y-647667D01*
X899500Y-647933D01*
X898900Y-648467D01*
X898500Y-649267D01*
X898300Y-650333D01*
X898500Y-651400D01*
X898900Y-652200D01*
X899500Y-652733D01*
X900200Y-653000D01*
X900900Y-652867D01*
X901500Y-652467D01*
X901900Y-651934D01*
G01X906400Y-653000D02*
Y-647667D01*
G01Y-649000D02*
X906800Y-648333D01*
X907400Y-647800D01*
X908200Y-647667D01*
X908900Y-647800D01*
X909500Y-648333D01*
X909800Y-649267D01*
Y-653000D01*
G01X916100Y-647667D02*
Y-653000D01*
G01Y-645533D02*
X915900Y-645400D01*
Y-645133D01*
X916100Y-645000D01*
X916300Y-645133D01*
Y-645400D01*
X916100Y-645533D01*
G01X925700Y-648333D02*
X925000Y-647800D01*
X924400Y-647667D01*
X923600Y-647933D01*
X923000Y-648467D01*
X922600Y-649400D01*
X922500Y-650333D01*
X922600Y-651267D01*
X923000Y-652067D01*
X923600Y-652733D01*
X924400Y-653000D01*
X925100Y-652733D01*
X925700Y-652200D01*
G01X933900Y-653000D02*
Y-647667D01*
G01Y-648600D02*
X933500Y-648067D01*
X932900Y-647800D01*
X932200Y-647667D01*
X931500Y-647933D01*
X930900Y-648467D01*
X930500Y-649267D01*
X930300Y-650333D01*
X930500Y-651400D01*
X930900Y-652200D01*
X931500Y-652733D01*
X932200Y-653000D01*
X932900Y-652867D01*
X933500Y-652467D01*
X933900Y-651934D01*
G01X940100Y-653000D02*
Y-645000D01*
G01X957900D02*
Y-653000D01*
G01Y-651800D02*
X957500Y-652467D01*
X956900Y-652867D01*
X956200Y-653000D01*
X955400Y-652733D01*
X954800Y-652067D01*
X954400Y-651267D01*
X954300Y-650333D01*
X954400Y-649400D01*
X954800Y-648600D01*
X955400Y-647933D01*
X956200Y-647667D01*
X956900Y-647800D01*
X957400Y-648067D01*
X957900Y-648600D01*
G01X962700Y-653000D02*
Y-647667D01*
G01Y-648733D02*
X963200Y-648200D01*
X963700Y-647800D01*
X964400Y-647667D01*
X964900Y-647800D01*
X965500Y-648200D01*
G01X973900Y-653000D02*
Y-647667D01*
G01Y-648600D02*
X973500Y-648067D01*
X972900Y-647800D01*
X972200Y-647667D01*
X971500Y-647933D01*
X970900Y-648467D01*
X970500Y-649267D01*
X970300Y-650333D01*
X970500Y-651400D01*
X970900Y-652200D01*
X971500Y-652733D01*
X972200Y-653000D01*
X972900Y-652867D01*
X973500Y-652467D01*
X973900Y-651934D01*
G01X977600Y-647667D02*
X978800Y-653000D01*
X980100Y-647667D01*
X981400Y-653000D01*
X982600Y-647667D01*
G01X988100D02*
Y-653000D01*
G01Y-645533D02*
X987900Y-645400D01*
Y-645133D01*
X988100Y-645000D01*
X988300Y-645133D01*
Y-645400D01*
X988100Y-645533D01*
G01X994400Y-653000D02*
Y-647667D01*
G01Y-649000D02*
X994800Y-648333D01*
X995400Y-647800D01*
X996200Y-647667D01*
X996900Y-647800D01*
X997500Y-648333D01*
X997800Y-649267D01*
Y-653000D01*
G01X1002700Y-655000D02*
X1003400Y-655533D01*
X1004200Y-655667D01*
X1004900Y-655533D01*
X1005500Y-654867D01*
X1005900Y-653933D01*
Y-647667D01*
G01Y-648733D02*
X1005500Y-648200D01*
X1004900Y-647800D01*
X1004200Y-647667D01*
X1003400Y-647933D01*
X1002900Y-648467D01*
X1002500Y-649400D01*
X1002300Y-650333D01*
X1002400Y-651133D01*
X1002800Y-652067D01*
X1003400Y-652733D01*
X1004200Y-653000D01*
X1004800Y-652867D01*
X1005500Y-652333D01*
X1005900Y-651800D01*
G01X1021900Y-653000D02*
Y-647667D01*
G01Y-648600D02*
X1021500Y-648067D01*
X1020900Y-647800D01*
X1020200Y-647667D01*
X1019500Y-647933D01*
X1018900Y-648467D01*
X1018500Y-649267D01*
X1018300Y-650333D01*
X1018500Y-651400D01*
X1018900Y-652200D01*
X1019500Y-652733D01*
X1020200Y-653000D01*
X1020900Y-652867D01*
X1021500Y-652467D01*
X1021900Y-651934D01*
G01X1026400Y-653000D02*
Y-647667D01*
G01Y-649000D02*
X1026800Y-648333D01*
X1027400Y-647800D01*
X1028200Y-647667D01*
X1028900Y-647800D01*
X1029500Y-648333D01*
X1029800Y-649267D01*
Y-653000D01*
G01X1037900Y-645000D02*
Y-653000D01*
G01Y-651800D02*
X1037500Y-652467D01*
X1036900Y-652867D01*
X1036200Y-653000D01*
X1035400Y-652733D01*
X1034800Y-652067D01*
X1034400Y-651267D01*
X1034300Y-650333D01*
X1034400Y-649400D01*
X1034800Y-648600D01*
X1035400Y-647933D01*
X1036200Y-647667D01*
X1036900Y-647800D01*
X1037400Y-648067D01*
X1037900Y-648600D01*
G01X1050400Y-653000D02*
Y-645000D01*
G01Y-648867D02*
X1050900Y-648200D01*
X1051400Y-647800D01*
X1052200Y-647667D01*
X1052800Y-647800D01*
X1053500Y-648333D01*
X1053800Y-649133D01*
Y-653000D01*
G01X1060100D02*
X1059500Y-652867D01*
X1058900Y-652333D01*
X1058500Y-651400D01*
X1058300Y-650333D01*
X1058500Y-649267D01*
X1058900Y-648333D01*
X1059500Y-647800D01*
X1060100Y-647667D01*
X1060700Y-647800D01*
X1061300Y-648333D01*
X1061700Y-649267D01*
X1061800Y-650333D01*
X1061700Y-651400D01*
X1061300Y-652333D01*
X1060700Y-652867D01*
X1060100Y-653000D01*
G01X1068100D02*
Y-645000D01*
G01X1074600Y-649400D02*
X1077800D01*
X1077500Y-648467D01*
X1077000Y-647933D01*
X1076300Y-647667D01*
X1075600Y-647800D01*
X1075000Y-648200D01*
X1074600Y-649133D01*
X1074400Y-649934D01*
Y-650733D01*
X1074600Y-651533D01*
X1075100Y-652333D01*
X1075700Y-652867D01*
X1076400Y-653000D01*
X1077100Y-652733D01*
X1077800Y-651934D01*
G01X1089900Y-653000D02*
Y-645000D01*
X1091900D01*
X1092700Y-645400D01*
X1093300Y-645933D01*
X1093800Y-646733D01*
X1094200Y-647667D01*
X1094300Y-649000D01*
X1094200Y-650333D01*
X1093800Y-651267D01*
X1093300Y-652067D01*
X1092700Y-652600D01*
X1091900Y-653000D01*
X1089900D01*
G01X1100100Y-647667D02*
Y-653000D01*
G01Y-645533D02*
X1099900Y-645400D01*
Y-645133D01*
X1100100Y-645000D01*
X1100300Y-645133D01*
Y-645400D01*
X1100100Y-645533D01*
G01X1109900Y-653000D02*
Y-647667D01*
G01Y-648600D02*
X1109500Y-648067D01*
X1108900Y-647800D01*
X1108200Y-647667D01*
X1107500Y-647933D01*
X1106900Y-648467D01*
X1106500Y-649267D01*
X1106300Y-650333D01*
X1106500Y-651400D01*
X1106900Y-652200D01*
X1107500Y-652733D01*
X1108200Y-653000D01*
X1108900Y-652867D01*
X1109500Y-652467D01*
X1109900Y-651934D01*
G01X1116100Y-653267D02*
X1115900Y-653133D01*
Y-652867D01*
X1116100Y-652733D01*
X1116300Y-652867D01*
Y-653133D01*
X1116100Y-653267D01*
G01X1132100Y-653000D02*
Y-645000D01*
X1130900Y-646600D01*
G01Y-653000D02*
X1133300D01*
G01X1138200Y-646333D02*
X1138800Y-645533D01*
X1139500Y-645133D01*
X1140300Y-645000D01*
X1141300Y-645267D01*
X1142000Y-645933D01*
X1142200Y-646733D01*
X1142100Y-647534D01*
X1141700Y-648200D01*
X1139700Y-649533D01*
X1138800Y-650467D01*
X1138200Y-651800D01*
X1138000Y-653000D01*
X1142200D01*
G01X1146200Y-649667D02*
X1146900Y-648733D01*
X1147500Y-648200D01*
X1148300Y-647933D01*
X1149000Y-648200D01*
X1149500Y-648733D01*
X1149900Y-649533D01*
X1150000Y-650467D01*
X1149900Y-651267D01*
X1149500Y-652067D01*
X1148900Y-652733D01*
X1148200Y-653000D01*
X1147400Y-652733D01*
X1146700Y-651934D01*
X1146300Y-650733D01*
X1146200Y-649400D01*
X1146400Y-647667D01*
X1146700Y-646733D01*
X1147200Y-645800D01*
X1147900Y-645133D01*
X1148600Y-645000D01*
X1149300Y-645267D01*
X1149800Y-645933D01*
G01X1153100Y-653000D02*
Y-647667D01*
G01Y-649133D02*
X1153400Y-648467D01*
X1153900Y-647933D01*
X1154600Y-647667D01*
X1155300Y-647933D01*
X1155800Y-648467D01*
X1156100Y-649133D01*
Y-653000D01*
G01Y-649133D02*
X1156400Y-648467D01*
X1156900Y-647933D01*
X1157600Y-647667D01*
X1158300Y-647933D01*
X1158800Y-648467D01*
X1159100Y-649267D01*
Y-653000D01*
G01X1164100Y-647667D02*
Y-653000D01*
G01Y-645533D02*
X1163900Y-645400D01*
Y-645133D01*
X1164100Y-645000D01*
X1164300Y-645133D01*
Y-645400D01*
X1164100Y-645533D01*
G01X1172100Y-653000D02*
Y-645000D01*
G01X1188100Y-647667D02*
Y-653000D01*
G01Y-645533D02*
X1187900Y-645400D01*
Y-645133D01*
X1188100Y-645000D01*
X1188300Y-645133D01*
Y-645400D01*
X1188100Y-645533D01*
G01X1194600Y-652067D02*
X1195100Y-652600D01*
X1195800Y-653000D01*
X1196400D01*
X1197000Y-652733D01*
X1197400Y-652333D01*
X1197600Y-651800D01*
X1197500Y-651000D01*
X1197100Y-650600D01*
X1195300Y-649800D01*
X1194900Y-648867D01*
X1195100Y-648200D01*
X1195500Y-647800D01*
X1196100Y-647667D01*
X1196700Y-647800D01*
X1197300Y-648200D01*
G01X1209100Y-653000D02*
Y-647667D01*
G01Y-649133D02*
X1209400Y-648467D01*
X1209900Y-647933D01*
X1210600Y-647667D01*
X1211300Y-647933D01*
X1211800Y-648467D01*
X1212100Y-649133D01*
Y-653000D01*
G01Y-649133D02*
X1212400Y-648467D01*
X1212900Y-647933D01*
X1213600Y-647667D01*
X1214300Y-647933D01*
X1214800Y-648467D01*
X1215100Y-649267D01*
Y-653000D01*
G01X1221900D02*
Y-647667D01*
G01Y-648600D02*
X1221500Y-648067D01*
X1220900Y-647800D01*
X1220200Y-647667D01*
X1219500Y-647933D01*
X1218900Y-648467D01*
X1218500Y-649267D01*
X1218300Y-650333D01*
X1218500Y-651400D01*
X1218900Y-652200D01*
X1219500Y-652733D01*
X1220200Y-653000D01*
X1220900Y-652867D01*
X1221500Y-652467D01*
X1221900Y-651934D01*
G01X1226700Y-653000D02*
Y-647667D01*
G01Y-648733D02*
X1227200Y-648200D01*
X1227700Y-647800D01*
X1228400Y-647667D01*
X1228900Y-647800D01*
X1229500Y-648200D01*
G01X1234400Y-653000D02*
Y-645000D01*
G01X1237600Y-647667D02*
X1234400Y-650733D01*
G01X1235700Y-649533D02*
X1237800Y-653000D01*
G01X1242600Y-649400D02*
X1245800D01*
X1245500Y-648467D01*
X1245000Y-647933D01*
X1244300Y-647667D01*
X1243600Y-647800D01*
X1243000Y-648200D01*
X1242600Y-649133D01*
X1242400Y-649934D01*
Y-650733D01*
X1242600Y-651533D01*
X1243100Y-652333D01*
X1243700Y-652867D01*
X1244400Y-653000D01*
X1245100Y-652733D01*
X1245800Y-651934D01*
G01X1253900Y-645000D02*
Y-653000D01*
G01Y-651800D02*
X1253500Y-652467D01*
X1252900Y-652867D01*
X1252200Y-653000D01*
X1251400Y-652733D01*
X1250800Y-652067D01*
X1250400Y-651267D01*
X1250300Y-650333D01*
X1250400Y-649400D01*
X1250800Y-648600D01*
X1251400Y-647933D01*
X1252200Y-647667D01*
X1252900Y-647800D01*
X1253400Y-648067D01*
X1253900Y-648600D01*
G01X1268100Y-647667D02*
Y-653000D01*
G01Y-645533D02*
X1267900Y-645400D01*
Y-645133D01*
X1268100Y-645000D01*
X1268300Y-645133D01*
Y-645400D01*
X1268100Y-645533D01*
G01X1274400Y-653000D02*
Y-647667D01*
G01Y-649000D02*
X1274800Y-648333D01*
X1275400Y-647800D01*
X1276200Y-647667D01*
X1276900Y-647800D01*
X1277500Y-648333D01*
X1277800Y-649267D01*
Y-653000D01*
G01X1292700Y-649000D02*
X1294700D01*
Y-651400D01*
X1294100Y-652200D01*
X1293400Y-652733D01*
X1292400Y-653000D01*
X1291400Y-652733D01*
X1290700Y-652200D01*
X1290100Y-651400D01*
X1289700Y-650467D01*
X1289500Y-649400D01*
Y-648467D01*
X1289700Y-647667D01*
X1290100Y-646733D01*
X1290700Y-645933D01*
X1291300Y-645400D01*
X1292100Y-645000D01*
X1292800D01*
X1293600Y-645267D01*
X1294200Y-645800D01*
G01X1298600Y-649400D02*
X1301800D01*
X1301500Y-648467D01*
X1301000Y-647933D01*
X1300300Y-647667D01*
X1299600Y-647800D01*
X1299000Y-648200D01*
X1298600Y-649133D01*
X1298400Y-649934D01*
Y-650733D01*
X1298600Y-651533D01*
X1299100Y-652333D01*
X1299700Y-652867D01*
X1300400Y-653000D01*
X1301100Y-652733D01*
X1301800Y-651934D01*
G01X1306700Y-653000D02*
Y-647667D01*
G01Y-648733D02*
X1307200Y-648200D01*
X1307700Y-647800D01*
X1308400Y-647667D01*
X1308900Y-647800D01*
X1309500Y-648200D01*
G01X1314300Y-653000D02*
Y-645000D01*
G01Y-649000D02*
X1314800Y-648200D01*
X1315400Y-647800D01*
X1316000Y-647667D01*
X1316900Y-647933D01*
X1317500Y-648467D01*
X1317900Y-649400D01*
Y-650467D01*
X1317700Y-651533D01*
X1317300Y-652333D01*
X1316600Y-652867D01*
X1316000Y-653000D01*
X1315400Y-652867D01*
X1314800Y-652467D01*
X1314300Y-651800D01*
G01X1322600Y-649400D02*
X1325800D01*
X1325500Y-648467D01*
X1325000Y-647933D01*
X1324300Y-647667D01*
X1323600Y-647800D01*
X1323000Y-648200D01*
X1322600Y-649133D01*
X1322400Y-649934D01*
Y-650733D01*
X1322600Y-651533D01*
X1323100Y-652333D01*
X1323700Y-652867D01*
X1324400Y-653000D01*
X1325100Y-652733D01*
X1325800Y-651934D01*
G01X1330700Y-653000D02*
Y-647667D01*
G01Y-648733D02*
X1331200Y-648200D01*
X1331700Y-647800D01*
X1332400Y-647667D01*
X1332900Y-647800D01*
X1333500Y-648200D01*
G01X1347500Y-653000D02*
Y-646200D01*
X1347700Y-645533D01*
X1348100Y-645133D01*
X1348700Y-645000D01*
X1349300Y-645267D01*
X1349600Y-645933D01*
G01X1348400Y-648200D02*
X1346400D01*
G01X1356100Y-647667D02*
Y-653000D01*
G01Y-645533D02*
X1355900Y-645400D01*
Y-645133D01*
X1356100Y-645000D01*
X1356300Y-645133D01*
Y-645400D01*
X1356100Y-645533D01*
G01X1364100Y-653000D02*
Y-645000D01*
G01X1370600Y-649400D02*
X1373800D01*
X1373500Y-648467D01*
X1373000Y-647933D01*
X1372300Y-647667D01*
X1371600Y-647800D01*
X1371000Y-648200D01*
X1370600Y-649133D01*
X1370400Y-649934D01*
Y-650733D01*
X1370600Y-651533D01*
X1371100Y-652333D01*
X1371700Y-652867D01*
X1372400Y-653000D01*
X1373100Y-652733D01*
X1373800Y-651934D01*
G01X1380100Y-653267D02*
X1379900Y-653133D01*
Y-652867D01*
X1380100Y-652733D01*
X1380300Y-652867D01*
Y-653133D01*
X1380100Y-653267D01*
G01X530400Y-633200D02*
X532800D01*
G01X531600D02*
Y-641200D01*
G01X530400D02*
X532800D01*
G01X539000D02*
Y-634400D01*
X539200Y-633733D01*
X539600Y-633333D01*
X540200Y-633200D01*
X540800Y-633467D01*
X541100Y-634133D01*
G01X539900Y-636400D02*
X537900D01*
G01X555600Y-635867D02*
Y-641200D01*
G01Y-633733D02*
X555400Y-633600D01*
Y-633333D01*
X555600Y-633200D01*
X555800Y-633333D01*
Y-633600D01*
X555600Y-633733D01*
G01X562100Y-640267D02*
X562600Y-640800D01*
X563300Y-641200D01*
X563900D01*
X564500Y-640933D01*
X564900Y-640533D01*
X565100Y-640000D01*
X565000Y-639200D01*
X564600Y-638800D01*
X562800Y-638000D01*
X562400Y-637067D01*
X562600Y-636400D01*
X563000Y-636000D01*
X563600Y-635867D01*
X564200Y-636000D01*
X564800Y-636400D01*
G01X578200Y-643200D02*
X578900Y-643733D01*
X579700Y-643867D01*
X580400Y-643733D01*
X581000Y-643067D01*
X581400Y-642133D01*
Y-635867D01*
G01Y-636933D02*
X581000Y-636400D01*
X580400Y-636000D01*
X579700Y-635867D01*
X578900Y-636133D01*
X578400Y-636667D01*
X578000Y-637600D01*
X577800Y-638533D01*
X577900Y-639333D01*
X578300Y-640267D01*
X578900Y-640933D01*
X579700Y-641200D01*
X580300Y-641067D01*
X581000Y-640533D01*
X581400Y-640000D01*
G01X586200Y-641200D02*
Y-635867D01*
G01Y-636933D02*
X586700Y-636400D01*
X587200Y-636000D01*
X587900Y-635867D01*
X588400Y-636000D01*
X589000Y-636400D01*
G01X594100Y-637600D02*
X597300D01*
X597000Y-636667D01*
X596500Y-636133D01*
X595800Y-635867D01*
X595100Y-636000D01*
X594500Y-636400D01*
X594100Y-637333D01*
X593900Y-638134D01*
Y-638933D01*
X594100Y-639733D01*
X594600Y-640533D01*
X595200Y-641067D01*
X595900Y-641200D01*
X596600Y-640933D01*
X597300Y-640134D01*
G01X605400Y-641200D02*
Y-635867D01*
G01Y-636800D02*
X605000Y-636267D01*
X604400Y-636000D01*
X603700Y-635867D01*
X603000Y-636133D01*
X602400Y-636667D01*
X602000Y-637467D01*
X601800Y-638533D01*
X602000Y-639600D01*
X602400Y-640400D01*
X603000Y-640933D01*
X603700Y-641200D01*
X604400Y-641067D01*
X605000Y-640667D01*
X605400Y-640134D01*
G01X611600Y-633200D02*
Y-641200D01*
G01X610200Y-635867D02*
X613000D01*
G01X618100Y-637600D02*
X621300D01*
X621000Y-636667D01*
X620500Y-636133D01*
X619800Y-635867D01*
X619100Y-636000D01*
X618500Y-636400D01*
X618100Y-637333D01*
X617900Y-638134D01*
Y-638933D01*
X618100Y-639733D01*
X618600Y-640533D01*
X619200Y-641067D01*
X619900Y-641200D01*
X620600Y-640933D01*
X621300Y-640134D01*
G01X626200Y-641200D02*
Y-635867D01*
G01Y-636933D02*
X626700Y-636400D01*
X627200Y-636000D01*
X627900Y-635867D01*
X628400Y-636000D01*
X629000Y-636400D01*
G01X643600Y-633200D02*
Y-641200D01*
G01X642200Y-635867D02*
X645000D01*
G01X649900Y-641200D02*
Y-633200D01*
G01Y-637067D02*
X650400Y-636400D01*
X650900Y-636000D01*
X651700Y-635867D01*
X652300Y-636000D01*
X653000Y-636533D01*
X653300Y-637333D01*
Y-641200D01*
G01X661400D02*
Y-635867D01*
G01Y-636800D02*
X661000Y-636267D01*
X660400Y-636000D01*
X659700Y-635867D01*
X659000Y-636133D01*
X658400Y-636667D01*
X658000Y-637467D01*
X657800Y-638533D01*
X658000Y-639600D01*
X658400Y-640400D01*
X659000Y-640933D01*
X659700Y-641200D01*
X660400Y-641067D01*
X661000Y-640667D01*
X661400Y-640134D01*
G01X665900Y-641200D02*
Y-635867D01*
G01Y-637200D02*
X666300Y-636533D01*
X666900Y-636000D01*
X667700Y-635867D01*
X668400Y-636000D01*
X669000Y-636533D01*
X669300Y-637467D01*
Y-641200D01*
G01X683600D02*
Y-633200D01*
X682400Y-634800D01*
G01Y-641200D02*
X684800D01*
G01X696600D02*
Y-635867D01*
G01Y-637333D02*
X696900Y-636667D01*
X697400Y-636133D01*
X698100Y-635867D01*
X698800Y-636133D01*
X699300Y-636667D01*
X699600Y-637333D01*
Y-641200D01*
G01Y-637333D02*
X699900Y-636667D01*
X700400Y-636133D01*
X701100Y-635867D01*
X701800Y-636133D01*
X702300Y-636667D01*
X702600Y-637467D01*
Y-641200D01*
G01X707600Y-635867D02*
Y-641200D01*
G01Y-633733D02*
X707400Y-633600D01*
Y-633333D01*
X707600Y-633200D01*
X707800Y-633333D01*
Y-633600D01*
X707600Y-633733D01*
G01X714100Y-640267D02*
X714600Y-640800D01*
X715300Y-641200D01*
X715900D01*
X716500Y-640933D01*
X716900Y-640533D01*
X717100Y-640000D01*
X717000Y-639200D01*
X716600Y-638800D01*
X714800Y-638000D01*
X714400Y-637067D01*
X714600Y-636400D01*
X715000Y-636000D01*
X715600Y-635867D01*
X716200Y-636000D01*
X716800Y-636400D01*
G01X723400Y-642667D02*
X723800Y-640933D01*
G01X737800Y-643867D02*
Y-635867D01*
G01Y-637067D02*
X738300Y-636400D01*
X738800Y-636000D01*
X739600Y-635867D01*
X740300Y-636000D01*
X741000Y-636667D01*
X741300Y-637600D01*
X741400Y-638533D01*
X741300Y-639467D01*
X741000Y-640400D01*
X740400Y-640933D01*
X739600Y-641200D01*
X738900Y-641067D01*
X738200Y-640667D01*
X737800Y-640134D01*
G01X747600Y-641200D02*
Y-633200D01*
G01X754100Y-637600D02*
X757300D01*
X757000Y-636667D01*
X756500Y-636133D01*
X755800Y-635867D01*
X755100Y-636000D01*
X754500Y-636400D01*
X754100Y-637333D01*
X753900Y-638134D01*
Y-638933D01*
X754100Y-639733D01*
X754600Y-640533D01*
X755200Y-641067D01*
X755900Y-641200D01*
X756600Y-640933D01*
X757300Y-640134D01*
G01X765400Y-641200D02*
Y-635867D01*
G01Y-636800D02*
X765000Y-636267D01*
X764400Y-636000D01*
X763700Y-635867D01*
X763000Y-636133D01*
X762400Y-636667D01*
X762000Y-637467D01*
X761800Y-638533D01*
X762000Y-639600D01*
X762400Y-640400D01*
X763000Y-640933D01*
X763700Y-641200D01*
X764400Y-641067D01*
X765000Y-640667D01*
X765400Y-640134D01*
G01X770100Y-640267D02*
X770600Y-640800D01*
X771300Y-641200D01*
X771900D01*
X772500Y-640933D01*
X772900Y-640533D01*
X773100Y-640000D01*
X773000Y-639200D01*
X772600Y-638800D01*
X770800Y-638000D01*
X770400Y-637067D01*
X770600Y-636400D01*
X771000Y-636000D01*
X771600Y-635867D01*
X772200Y-636000D01*
X772800Y-636400D01*
G01X778100Y-637600D02*
X781300D01*
X781000Y-636667D01*
X780500Y-636133D01*
X779800Y-635867D01*
X779100Y-636000D01*
X778500Y-636400D01*
X778100Y-637333D01*
X777900Y-638134D01*
Y-638933D01*
X778100Y-639733D01*
X778600Y-640533D01*
X779200Y-641067D01*
X779900Y-641200D01*
X780600Y-640933D01*
X781300Y-640134D01*
G01X795600Y-635867D02*
Y-641200D01*
G01Y-633733D02*
X795400Y-633600D01*
Y-633333D01*
X795600Y-633200D01*
X795800Y-633333D01*
Y-633600D01*
X795600Y-633733D01*
G01X802100Y-640267D02*
X802600Y-640800D01*
X803300Y-641200D01*
X803900D01*
X804500Y-640933D01*
X804900Y-640533D01*
X805100Y-640000D01*
X805000Y-639200D01*
X804600Y-638800D01*
X802800Y-638000D01*
X802400Y-637067D01*
X802600Y-636400D01*
X803000Y-636000D01*
X803600Y-635867D01*
X804200Y-636000D01*
X804800Y-636400D01*
G01X810100Y-640267D02*
X810600Y-640800D01*
X811300Y-641200D01*
X811900D01*
X812500Y-640933D01*
X812900Y-640533D01*
X813100Y-640000D01*
X813000Y-639200D01*
X812600Y-638800D01*
X810800Y-638000D01*
X810400Y-637067D01*
X810600Y-636400D01*
X811000Y-636000D01*
X811600Y-635867D01*
X812200Y-636000D01*
X812800Y-636400D01*
G01X817900Y-635867D02*
Y-639600D01*
X818300Y-640533D01*
X818900Y-641067D01*
X819600Y-641200D01*
X820300Y-641067D01*
X820900Y-640533D01*
X821300Y-639600D01*
G01Y-641200D02*
Y-635867D01*
G01X826100Y-637600D02*
X829300D01*
X829000Y-636667D01*
X828500Y-636133D01*
X827800Y-635867D01*
X827100Y-636000D01*
X826500Y-636400D01*
X826100Y-637333D01*
X825900Y-638134D01*
Y-638933D01*
X826100Y-639733D01*
X826600Y-640533D01*
X827200Y-641067D01*
X827900Y-641200D01*
X828600Y-640933D01*
X829300Y-640134D01*
G01X842100Y-637600D02*
X845300D01*
X845000Y-636667D01*
X844500Y-636133D01*
X843800Y-635867D01*
X843100Y-636000D01*
X842500Y-636400D01*
X842100Y-637333D01*
X841900Y-638134D01*
Y-638933D01*
X842100Y-639733D01*
X842600Y-640533D01*
X843200Y-641067D01*
X843900Y-641200D01*
X844600Y-640933D01*
X845300Y-640134D01*
G01X849900Y-641200D02*
Y-635867D01*
G01Y-637200D02*
X850300Y-636533D01*
X850900Y-636000D01*
X851700Y-635867D01*
X852400Y-636000D01*
X853000Y-636533D01*
X853300Y-637467D01*
Y-641200D01*
G01X858200Y-643200D02*
X858900Y-643733D01*
X859700Y-643867D01*
X860400Y-643733D01*
X861000Y-643067D01*
X861400Y-642133D01*
Y-635867D01*
G01Y-636933D02*
X861000Y-636400D01*
X860400Y-636000D01*
X859700Y-635867D01*
X858900Y-636133D01*
X858400Y-636667D01*
X858000Y-637600D01*
X857800Y-638533D01*
X857900Y-639333D01*
X858300Y-640267D01*
X858900Y-640933D01*
X859700Y-641200D01*
X860300Y-641067D01*
X861000Y-640533D01*
X861400Y-640000D01*
G01X867600Y-635867D02*
Y-641200D01*
G01Y-633733D02*
X867400Y-633600D01*
Y-633333D01*
X867600Y-633200D01*
X867800Y-633333D01*
Y-633600D01*
X867600Y-633733D01*
G01X873900Y-641200D02*
Y-635867D01*
G01Y-637200D02*
X874300Y-636533D01*
X874900Y-636000D01*
X875700Y-635867D01*
X876400Y-636000D01*
X877000Y-636533D01*
X877300Y-637467D01*
Y-641200D01*
G01X882100Y-637600D02*
X885300D01*
X885000Y-636667D01*
X884500Y-636133D01*
X883800Y-635867D01*
X883100Y-636000D01*
X882500Y-636400D01*
X882100Y-637333D01*
X881900Y-638134D01*
Y-638933D01*
X882100Y-639733D01*
X882600Y-640533D01*
X883200Y-641067D01*
X883900Y-641200D01*
X884600Y-640933D01*
X885300Y-640134D01*
G01X890100Y-637600D02*
X893300D01*
X893000Y-636667D01*
X892500Y-636133D01*
X891800Y-635867D01*
X891100Y-636000D01*
X890500Y-636400D01*
X890100Y-637333D01*
X889900Y-638134D01*
Y-638933D01*
X890100Y-639733D01*
X890600Y-640533D01*
X891200Y-641067D01*
X891900Y-641200D01*
X892600Y-640933D01*
X893300Y-640134D01*
G01X898200Y-641200D02*
Y-635867D01*
G01Y-636933D02*
X898700Y-636400D01*
X899200Y-636000D01*
X899900Y-635867D01*
X900400Y-636000D01*
X901000Y-636400D01*
G01X907600Y-635867D02*
Y-641200D01*
G01Y-633733D02*
X907400Y-633600D01*
Y-633333D01*
X907600Y-633200D01*
X907800Y-633333D01*
Y-633600D01*
X907600Y-633733D01*
G01X913900Y-641200D02*
Y-635867D01*
G01Y-637200D02*
X914300Y-636533D01*
X914900Y-636000D01*
X915700Y-635867D01*
X916400Y-636000D01*
X917000Y-636533D01*
X917300Y-637467D01*
Y-641200D01*
G01X922200Y-643200D02*
X922900Y-643733D01*
X923700Y-643867D01*
X924400Y-643733D01*
X925000Y-643067D01*
X925400Y-642133D01*
Y-635867D01*
G01Y-636933D02*
X925000Y-636400D01*
X924400Y-636000D01*
X923700Y-635867D01*
X922900Y-636133D01*
X922400Y-636667D01*
X922000Y-637600D01*
X921800Y-638533D01*
X921900Y-639333D01*
X922300Y-640267D01*
X922900Y-640933D01*
X923700Y-641200D01*
X924300Y-641067D01*
X925000Y-640533D01*
X925400Y-640000D01*
G01X941400Y-643867D02*
Y-635867D01*
G01Y-637067D02*
X940900Y-636400D01*
X940300Y-636000D01*
X939600Y-635867D01*
X939000Y-636000D01*
X938300Y-636667D01*
X937900Y-637600D01*
X937800Y-638533D01*
X937900Y-639467D01*
X938300Y-640400D01*
X939000Y-641067D01*
X939600Y-641200D01*
X940300Y-641067D01*
X940900Y-640667D01*
X941400Y-640000D01*
G01X945900Y-635867D02*
Y-639600D01*
X946300Y-640533D01*
X946900Y-641067D01*
X947600Y-641200D01*
X948300Y-641067D01*
X948900Y-640533D01*
X949300Y-639600D01*
G01Y-641200D02*
Y-635867D01*
G01X954100Y-637600D02*
X957300D01*
X957000Y-636667D01*
X956500Y-636133D01*
X955800Y-635867D01*
X955100Y-636000D01*
X954500Y-636400D01*
X954100Y-637333D01*
X953900Y-638134D01*
Y-638933D01*
X954100Y-639733D01*
X954600Y-640533D01*
X955200Y-641067D01*
X955900Y-641200D01*
X956600Y-640933D01*
X957300Y-640134D01*
G01X962200Y-641200D02*
Y-635867D01*
G01Y-636933D02*
X962700Y-636400D01*
X963200Y-636000D01*
X963900Y-635867D01*
X964400Y-636000D01*
X965000Y-636400D01*
G01X969500Y-643600D02*
X970100Y-643867D01*
X970900Y-643600D01*
X971400Y-643067D01*
X971800Y-642400D01*
X972400Y-640267D01*
X973700Y-635867D01*
G01X970500D02*
X972400Y-640267D01*
G01X979600Y-641467D02*
X979400Y-641333D01*
Y-641067D01*
X979600Y-640933D01*
X979800Y-641067D01*
Y-641333D01*
X979600Y-641467D01*
G01X530200Y-620900D02*
Y-626633D01*
X530600Y-627834D01*
X531400Y-628633D01*
X532400Y-628900D01*
X533400Y-628633D01*
X534200Y-627834D01*
X534600Y-626633D01*
Y-620900D01*
G01X538700Y-628900D02*
Y-623567D01*
G01Y-624900D02*
X539100Y-624233D01*
X539700Y-623700D01*
X540500Y-623567D01*
X541200Y-623700D01*
X541800Y-624233D01*
X542100Y-625167D01*
Y-628900D01*
G01X548400Y-623567D02*
Y-628900D01*
G01Y-621433D02*
X548200Y-621300D01*
Y-621033D01*
X548400Y-620900D01*
X548600Y-621033D01*
Y-621300D01*
X548400Y-621433D01*
G01X556400Y-620900D02*
Y-628900D01*
G01X555000Y-623567D02*
X557800D01*
G01X574000Y-624233D02*
X573300Y-623700D01*
X572700Y-623567D01*
X571900Y-623833D01*
X571300Y-624367D01*
X570900Y-625300D01*
X570800Y-626233D01*
X570900Y-627167D01*
X571300Y-627967D01*
X571900Y-628633D01*
X572700Y-628900D01*
X573400Y-628633D01*
X574000Y-628100D01*
G01X580400Y-628900D02*
X579800Y-628767D01*
X579200Y-628233D01*
X578800Y-627300D01*
X578600Y-626233D01*
X578800Y-625167D01*
X579200Y-624233D01*
X579800Y-623700D01*
X580400Y-623567D01*
X581000Y-623700D01*
X581600Y-624233D01*
X582000Y-625167D01*
X582100Y-626233D01*
X582000Y-627300D01*
X581600Y-628233D01*
X581000Y-628767D01*
X580400Y-628900D01*
G01X586700D02*
Y-623567D01*
G01Y-624900D02*
X587100Y-624233D01*
X587700Y-623700D01*
X588500Y-623567D01*
X589200Y-623700D01*
X589800Y-624233D01*
X590100Y-625167D01*
Y-628900D01*
G01X594600Y-623567D02*
X596400Y-628900D01*
X598200Y-623567D01*
G01X602900Y-625300D02*
X606100D01*
X605800Y-624367D01*
X605300Y-623833D01*
X604600Y-623567D01*
X603900Y-623700D01*
X603300Y-624100D01*
X602900Y-625033D01*
X602700Y-625834D01*
Y-626633D01*
X602900Y-627433D01*
X603400Y-628233D01*
X604000Y-628767D01*
X604700Y-628900D01*
X605400Y-628633D01*
X606100Y-627834D01*
G01X611000Y-628900D02*
Y-623567D01*
G01Y-624633D02*
X611500Y-624100D01*
X612000Y-623700D01*
X612700Y-623567D01*
X613200Y-623700D01*
X613800Y-624100D01*
G01X618900Y-627967D02*
X619400Y-628500D01*
X620100Y-628900D01*
X620700D01*
X621300Y-628633D01*
X621700Y-628233D01*
X621900Y-627700D01*
X621800Y-626900D01*
X621400Y-626500D01*
X619600Y-625700D01*
X619200Y-624767D01*
X619400Y-624100D01*
X619800Y-623700D01*
X620400Y-623567D01*
X621000Y-623700D01*
X621600Y-624100D01*
G01X628400Y-623567D02*
Y-628900D01*
G01Y-621433D02*
X628200Y-621300D01*
Y-621033D01*
X628400Y-620900D01*
X628600Y-621033D01*
Y-621300D01*
X628400Y-621433D01*
G01X636400Y-628900D02*
X635800Y-628767D01*
X635200Y-628233D01*
X634800Y-627300D01*
X634600Y-626233D01*
X634800Y-625167D01*
X635200Y-624233D01*
X635800Y-623700D01*
X636400Y-623567D01*
X637000Y-623700D01*
X637600Y-624233D01*
X638000Y-625167D01*
X638100Y-626233D01*
X638000Y-627300D01*
X637600Y-628233D01*
X637000Y-628767D01*
X636400Y-628900D01*
G01X642700D02*
Y-623567D01*
G01Y-624900D02*
X643100Y-624233D01*
X643700Y-623700D01*
X644500Y-623567D01*
X645200Y-623700D01*
X645800Y-624233D01*
X646100Y-625167D01*
Y-628900D01*
G01X658900Y-625300D02*
X662100D01*
X661800Y-624367D01*
X661300Y-623833D01*
X660600Y-623567D01*
X659900Y-623700D01*
X659300Y-624100D01*
X658900Y-625033D01*
X658700Y-625834D01*
Y-626633D01*
X658900Y-627433D01*
X659400Y-628233D01*
X660000Y-628767D01*
X660700Y-628900D01*
X661400Y-628633D01*
X662100Y-627834D01*
G01X667000Y-628900D02*
Y-623567D01*
G01Y-624633D02*
X667500Y-624100D01*
X668000Y-623700D01*
X668700Y-623567D01*
X669200Y-623700D01*
X669800Y-624100D01*
G01X675000Y-628900D02*
Y-623567D01*
G01Y-624633D02*
X675500Y-624100D01*
X676000Y-623700D01*
X676700Y-623567D01*
X677200Y-623700D01*
X677800Y-624100D01*
G01X684400Y-628900D02*
X683800Y-628767D01*
X683200Y-628233D01*
X682800Y-627300D01*
X682600Y-626233D01*
X682800Y-625167D01*
X683200Y-624233D01*
X683800Y-623700D01*
X684400Y-623567D01*
X685000Y-623700D01*
X685600Y-624233D01*
X686000Y-625167D01*
X686100Y-626233D01*
X686000Y-627300D01*
X685600Y-628233D01*
X685000Y-628767D01*
X684400Y-628900D01*
G01X691000D02*
Y-623567D01*
G01Y-624633D02*
X691500Y-624100D01*
X692000Y-623700D01*
X692700Y-623567D01*
X693200Y-623700D01*
X693800Y-624100D01*
G01X706600Y-628900D02*
Y-620900D01*
G01Y-624900D02*
X707100Y-624100D01*
X707700Y-623700D01*
X708300Y-623567D01*
X709200Y-623833D01*
X709800Y-624367D01*
X710200Y-625300D01*
Y-626367D01*
X710000Y-627433D01*
X709600Y-628233D01*
X708900Y-628767D01*
X708300Y-628900D01*
X707700Y-628767D01*
X707100Y-628367D01*
X706600Y-627700D01*
G01X714900Y-625300D02*
X718100D01*
X717800Y-624367D01*
X717300Y-623833D01*
X716600Y-623567D01*
X715900Y-623700D01*
X715300Y-624100D01*
X714900Y-625033D01*
X714700Y-625834D01*
Y-626633D01*
X714900Y-627433D01*
X715400Y-628233D01*
X716000Y-628767D01*
X716700Y-628900D01*
X717400Y-628633D01*
X718100Y-627834D01*
G01X724400Y-620900D02*
Y-628900D01*
G01X723000Y-623567D02*
X725800D01*
G01X729900D02*
X731100Y-628900D01*
X732400Y-623567D01*
X733700Y-628900D01*
X734900Y-623567D01*
G01X738900Y-625300D02*
X742100D01*
X741800Y-624367D01*
X741300Y-623833D01*
X740600Y-623567D01*
X739900Y-623700D01*
X739300Y-624100D01*
X738900Y-625033D01*
X738700Y-625834D01*
Y-626633D01*
X738900Y-627433D01*
X739400Y-628233D01*
X740000Y-628767D01*
X740700Y-628900D01*
X741400Y-628633D01*
X742100Y-627834D01*
G01X746900Y-625300D02*
X750100D01*
X749800Y-624367D01*
X749300Y-623833D01*
X748600Y-623567D01*
X747900Y-623700D01*
X747300Y-624100D01*
X746900Y-625033D01*
X746700Y-625834D01*
Y-626633D01*
X746900Y-627433D01*
X747400Y-628233D01*
X748000Y-628767D01*
X748700Y-628900D01*
X749400Y-628633D01*
X750100Y-627834D01*
G01X754700Y-628900D02*
Y-623567D01*
G01Y-624900D02*
X755100Y-624233D01*
X755700Y-623700D01*
X756500Y-623567D01*
X757200Y-623700D01*
X757800Y-624233D01*
X758100Y-625167D01*
Y-628900D01*
G01X769400D02*
Y-623567D01*
G01Y-625033D02*
X769700Y-624367D01*
X770200Y-623833D01*
X770900Y-623567D01*
X771600Y-623833D01*
X772100Y-624367D01*
X772400Y-625033D01*
Y-628900D01*
G01Y-625033D02*
X772700Y-624367D01*
X773200Y-623833D01*
X773900Y-623567D01*
X774600Y-623833D01*
X775100Y-624367D01*
X775400Y-625167D01*
Y-628900D01*
G01X778900Y-625300D02*
X782100D01*
X781800Y-624367D01*
X781300Y-623833D01*
X780600Y-623567D01*
X779900Y-623700D01*
X779300Y-624100D01*
X778900Y-625033D01*
X778700Y-625834D01*
Y-626633D01*
X778900Y-627433D01*
X779400Y-628233D01*
X780000Y-628767D01*
X780700Y-628900D01*
X781400Y-628633D01*
X782100Y-627834D01*
G01X788400Y-620900D02*
Y-628900D01*
G01X787000Y-623567D02*
X789800D01*
G01X795000Y-628900D02*
Y-623567D01*
G01Y-624633D02*
X795500Y-624100D01*
X796000Y-623700D01*
X796700Y-623567D01*
X797200Y-623700D01*
X797800Y-624100D01*
G01X804400Y-623567D02*
Y-628900D01*
G01Y-621433D02*
X804200Y-621300D01*
Y-621033D01*
X804400Y-620900D01*
X804600Y-621033D01*
Y-621300D01*
X804400Y-621433D01*
G01X814000Y-624233D02*
X813300Y-623700D01*
X812700Y-623567D01*
X811900Y-623833D01*
X811300Y-624367D01*
X810900Y-625300D01*
X810800Y-626233D01*
X810900Y-627167D01*
X811300Y-627967D01*
X811900Y-628633D01*
X812700Y-628900D01*
X813400Y-628633D01*
X814000Y-628100D01*
G01X830200Y-628900D02*
Y-623567D01*
G01Y-624500D02*
X829800Y-623967D01*
X829200Y-623700D01*
X828500Y-623567D01*
X827800Y-623833D01*
X827200Y-624367D01*
X826800Y-625167D01*
X826600Y-626233D01*
X826800Y-627300D01*
X827200Y-628100D01*
X827800Y-628633D01*
X828500Y-628900D01*
X829200Y-628767D01*
X829800Y-628367D01*
X830200Y-627834D01*
G01X834700Y-628900D02*
Y-623567D01*
G01Y-624900D02*
X835100Y-624233D01*
X835700Y-623700D01*
X836500Y-623567D01*
X837200Y-623700D01*
X837800Y-624233D01*
X838100Y-625167D01*
Y-628900D01*
G01X846200Y-620900D02*
Y-628900D01*
G01Y-627700D02*
X845800Y-628367D01*
X845200Y-628767D01*
X844500Y-628900D01*
X843700Y-628633D01*
X843100Y-627967D01*
X842700Y-627167D01*
X842600Y-626233D01*
X842700Y-625300D01*
X843100Y-624500D01*
X843700Y-623833D01*
X844500Y-623567D01*
X845200Y-623700D01*
X845700Y-623967D01*
X846200Y-624500D01*
G01X862400Y-628900D02*
X858400D01*
Y-620900D01*
X862400D01*
G01X860800Y-624767D02*
X858400D01*
G01X866700Y-628900D02*
Y-623567D01*
G01Y-624900D02*
X867100Y-624233D01*
X867700Y-623700D01*
X868500Y-623567D01*
X869200Y-623700D01*
X869800Y-624233D01*
X870100Y-625167D01*
Y-628900D01*
G01X875000Y-630900D02*
X875700Y-631433D01*
X876500Y-631567D01*
X877200Y-631433D01*
X877800Y-630767D01*
X878200Y-629833D01*
Y-623567D01*
G01Y-624633D02*
X877800Y-624100D01*
X877200Y-623700D01*
X876500Y-623567D01*
X875700Y-623833D01*
X875200Y-624367D01*
X874800Y-625300D01*
X874600Y-626233D01*
X874700Y-627033D01*
X875100Y-627967D01*
X875700Y-628633D01*
X876500Y-628900D01*
X877100Y-628767D01*
X877800Y-628233D01*
X878200Y-627700D01*
G01X884400Y-628900D02*
Y-620900D01*
G01X892400Y-623567D02*
Y-628900D01*
G01Y-621433D02*
X892200Y-621300D01*
Y-621033D01*
X892400Y-620900D01*
X892600Y-621033D01*
Y-621300D01*
X892400Y-621433D01*
G01X898900Y-627967D02*
X899400Y-628500D01*
X900100Y-628900D01*
X900700D01*
X901300Y-628633D01*
X901700Y-628233D01*
X901900Y-627700D01*
X901800Y-626900D01*
X901400Y-626500D01*
X899600Y-625700D01*
X899200Y-624767D01*
X899400Y-624100D01*
X899800Y-623700D01*
X900400Y-623567D01*
X901000Y-623700D01*
X901600Y-624100D01*
G01X906700Y-628900D02*
Y-620900D01*
G01Y-624767D02*
X907200Y-624100D01*
X907700Y-623700D01*
X908500Y-623567D01*
X909100Y-623700D01*
X909800Y-624233D01*
X910100Y-625033D01*
Y-628900D01*
G01X922900Y-627967D02*
X923400Y-628500D01*
X924100Y-628900D01*
X924700D01*
X925300Y-628633D01*
X925700Y-628233D01*
X925900Y-627700D01*
X925800Y-626900D01*
X925400Y-626500D01*
X923600Y-625700D01*
X923200Y-624767D01*
X923400Y-624100D01*
X923800Y-623700D01*
X924400Y-623567D01*
X925000Y-623700D01*
X925600Y-624100D01*
G01X930300Y-631300D02*
X930900Y-631567D01*
X931700Y-631300D01*
X932200Y-630767D01*
X932600Y-630100D01*
X933200Y-627967D01*
X934500Y-623567D01*
G01X931300D02*
X933200Y-627967D01*
G01X938900D02*
X939400Y-628500D01*
X940100Y-628900D01*
X940700D01*
X941300Y-628633D01*
X941700Y-628233D01*
X941900Y-627700D01*
X941800Y-626900D01*
X941400Y-626500D01*
X939600Y-625700D01*
X939200Y-624767D01*
X939400Y-624100D01*
X939800Y-623700D01*
X940400Y-623567D01*
X941000Y-623700D01*
X941600Y-624100D01*
G01X948400Y-620900D02*
Y-628900D01*
G01X947000Y-623567D02*
X949800D01*
G01X954900Y-625300D02*
X958100D01*
X957800Y-624367D01*
X957300Y-623833D01*
X956600Y-623567D01*
X955900Y-623700D01*
X955300Y-624100D01*
X954900Y-625033D01*
X954700Y-625834D01*
Y-626633D01*
X954900Y-627433D01*
X955400Y-628233D01*
X956000Y-628767D01*
X956700Y-628900D01*
X957400Y-628633D01*
X958100Y-627834D01*
G01X961400Y-628900D02*
Y-623567D01*
G01Y-625033D02*
X961700Y-624367D01*
X962200Y-623833D01*
X962900Y-623567D01*
X963600Y-623833D01*
X964100Y-624367D01*
X964400Y-625033D01*
Y-628900D01*
G01Y-625033D02*
X964700Y-624367D01*
X965200Y-623833D01*
X965900Y-623567D01*
X966600Y-623833D01*
X967100Y-624367D01*
X967400Y-625167D01*
Y-628900D01*
G01X980400Y-623567D02*
Y-628900D01*
G01Y-621433D02*
X980200Y-621300D01*
Y-621033D01*
X980400Y-620900D01*
X980600Y-621033D01*
Y-621300D01*
X980400Y-621433D01*
G01X986900Y-627967D02*
X987400Y-628500D01*
X988100Y-628900D01*
X988700D01*
X989300Y-628633D01*
X989700Y-628233D01*
X989900Y-627700D01*
X989800Y-626900D01*
X989400Y-626500D01*
X987600Y-625700D01*
X987200Y-624767D01*
X987400Y-624100D01*
X987800Y-623700D01*
X988400Y-623567D01*
X989000Y-623700D01*
X989600Y-624100D01*
G01X1004400Y-628900D02*
Y-620900D01*
G01X1010900Y-625300D02*
X1014100D01*
X1013800Y-624367D01*
X1013300Y-623833D01*
X1012600Y-623567D01*
X1011900Y-623700D01*
X1011300Y-624100D01*
X1010900Y-625033D01*
X1010700Y-625834D01*
Y-626633D01*
X1010900Y-627433D01*
X1011400Y-628233D01*
X1012000Y-628767D01*
X1012700Y-628900D01*
X1013400Y-628633D01*
X1014100Y-627834D01*
G01X1018900Y-627967D02*
X1019400Y-628500D01*
X1020100Y-628900D01*
X1020700D01*
X1021300Y-628633D01*
X1021700Y-628233D01*
X1021900Y-627700D01*
X1021800Y-626900D01*
X1021400Y-626500D01*
X1019600Y-625700D01*
X1019200Y-624767D01*
X1019400Y-624100D01*
X1019800Y-623700D01*
X1020400Y-623567D01*
X1021000Y-623700D01*
X1021600Y-624100D01*
G01X1026900Y-627967D02*
X1027400Y-628500D01*
X1028100Y-628900D01*
X1028700D01*
X1029300Y-628633D01*
X1029700Y-628233D01*
X1029900Y-627700D01*
X1029800Y-626900D01*
X1029400Y-626500D01*
X1027600Y-625700D01*
X1027200Y-624767D01*
X1027400Y-624100D01*
X1027800Y-623700D01*
X1028400Y-623567D01*
X1029000Y-623700D01*
X1029600Y-624100D01*
G01X1044400Y-620900D02*
Y-628900D01*
G01X1043000Y-623567D02*
X1045800D01*
G01X1050700Y-628900D02*
Y-620900D01*
G01Y-624767D02*
X1051200Y-624100D01*
X1051700Y-623700D01*
X1052500Y-623567D01*
X1053100Y-623700D01*
X1053800Y-624233D01*
X1054100Y-625033D01*
Y-628900D01*
G01X1062200D02*
Y-623567D01*
G01Y-624500D02*
X1061800Y-623967D01*
X1061200Y-623700D01*
X1060500Y-623567D01*
X1059800Y-623833D01*
X1059200Y-624367D01*
X1058800Y-625167D01*
X1058600Y-626233D01*
X1058800Y-627300D01*
X1059200Y-628100D01*
X1059800Y-628633D01*
X1060500Y-628900D01*
X1061200Y-628767D01*
X1061800Y-628367D01*
X1062200Y-627834D01*
G01X1066700Y-628900D02*
Y-623567D01*
G01Y-624900D02*
X1067100Y-624233D01*
X1067700Y-623700D01*
X1068500Y-623567D01*
X1069200Y-623700D01*
X1069800Y-624233D01*
X1070100Y-625167D01*
Y-628900D01*
G01X1084400D02*
Y-620900D01*
X1083200Y-622500D01*
G01Y-628900D02*
X1085600D01*
G01X1097400D02*
Y-623567D01*
G01Y-625033D02*
X1097700Y-624367D01*
X1098200Y-623833D01*
X1098900Y-623567D01*
X1099600Y-623833D01*
X1100100Y-624367D01*
X1100400Y-625033D01*
Y-628900D01*
G01Y-625033D02*
X1100700Y-624367D01*
X1101200Y-623833D01*
X1101900Y-623567D01*
X1102600Y-623833D01*
X1103100Y-624367D01*
X1103400Y-625167D01*
Y-628900D01*
G01X1108400Y-623567D02*
Y-628900D01*
G01Y-621433D02*
X1108200Y-621300D01*
Y-621033D01*
X1108400Y-620900D01*
X1108600Y-621033D01*
Y-621300D01*
X1108400Y-621433D01*
G01X1116400Y-628900D02*
Y-620900D01*
G01X1124200Y-630367D02*
X1124600Y-628633D01*
G01X1138600Y-631567D02*
Y-623567D01*
G01Y-624767D02*
X1139100Y-624100D01*
X1139600Y-623700D01*
X1140400Y-623567D01*
X1141100Y-623700D01*
X1141800Y-624367D01*
X1142100Y-625300D01*
X1142200Y-626233D01*
X1142100Y-627167D01*
X1141800Y-628100D01*
X1141200Y-628633D01*
X1140400Y-628900D01*
X1139700Y-628767D01*
X1139000Y-628367D01*
X1138600Y-627834D01*
G01X1148400Y-628900D02*
Y-620900D01*
G01X1154900Y-625300D02*
X1158100D01*
X1157800Y-624367D01*
X1157300Y-623833D01*
X1156600Y-623567D01*
X1155900Y-623700D01*
X1155300Y-624100D01*
X1154900Y-625033D01*
X1154700Y-625834D01*
Y-626633D01*
X1154900Y-627433D01*
X1155400Y-628233D01*
X1156000Y-628767D01*
X1156700Y-628900D01*
X1157400Y-628633D01*
X1158100Y-627834D01*
G01X1166200Y-628900D02*
Y-623567D01*
G01Y-624500D02*
X1165800Y-623967D01*
X1165200Y-623700D01*
X1164500Y-623567D01*
X1163800Y-623833D01*
X1163200Y-624367D01*
X1162800Y-625167D01*
X1162600Y-626233D01*
X1162800Y-627300D01*
X1163200Y-628100D01*
X1163800Y-628633D01*
X1164500Y-628900D01*
X1165200Y-628767D01*
X1165800Y-628367D01*
X1166200Y-627834D01*
G01X1170900Y-627967D02*
X1171400Y-628500D01*
X1172100Y-628900D01*
X1172700D01*
X1173300Y-628633D01*
X1173700Y-628233D01*
X1173900Y-627700D01*
X1173800Y-626900D01*
X1173400Y-626500D01*
X1171600Y-625700D01*
X1171200Y-624767D01*
X1171400Y-624100D01*
X1171800Y-623700D01*
X1172400Y-623567D01*
X1173000Y-623700D01*
X1173600Y-624100D01*
G01X1178900Y-625300D02*
X1182100D01*
X1181800Y-624367D01*
X1181300Y-623833D01*
X1180600Y-623567D01*
X1179900Y-623700D01*
X1179300Y-624100D01*
X1178900Y-625033D01*
X1178700Y-625834D01*
Y-626633D01*
X1178900Y-627433D01*
X1179400Y-628233D01*
X1180000Y-628767D01*
X1180700Y-628900D01*
X1181400Y-628633D01*
X1182100Y-627834D01*
G01X1195800Y-628900D02*
Y-622100D01*
X1196000Y-621433D01*
X1196400Y-621033D01*
X1197000Y-620900D01*
X1197600Y-621167D01*
X1197900Y-621833D01*
G01X1196700Y-624100D02*
X1194700D01*
G01X1204400Y-628900D02*
X1203800Y-628767D01*
X1203200Y-628233D01*
X1202800Y-627300D01*
X1202600Y-626233D01*
X1202800Y-625167D01*
X1203200Y-624233D01*
X1203800Y-623700D01*
X1204400Y-623567D01*
X1205000Y-623700D01*
X1205600Y-624233D01*
X1206000Y-625167D01*
X1206100Y-626233D01*
X1206000Y-627300D01*
X1205600Y-628233D01*
X1205000Y-628767D01*
X1204400Y-628900D01*
G01X1212400D02*
Y-620900D01*
G01X1220400Y-628900D02*
Y-620900D01*
G01X1228400Y-628900D02*
X1227800Y-628767D01*
X1227200Y-628233D01*
X1226800Y-627300D01*
X1226600Y-626233D01*
X1226800Y-625167D01*
X1227200Y-624233D01*
X1227800Y-623700D01*
X1228400Y-623567D01*
X1229000Y-623700D01*
X1229600Y-624233D01*
X1230000Y-625167D01*
X1230100Y-626233D01*
X1230000Y-627300D01*
X1229600Y-628233D01*
X1229000Y-628767D01*
X1228400Y-628900D01*
G01X1233900Y-623567D02*
X1235100Y-628900D01*
X1236400Y-623567D01*
X1237700Y-628900D01*
X1238900Y-623567D01*
G01X1249400Y-628900D02*
Y-623567D01*
G01Y-625033D02*
X1249700Y-624367D01*
X1250200Y-623833D01*
X1250900Y-623567D01*
X1251600Y-623833D01*
X1252100Y-624367D01*
X1252400Y-625033D01*
Y-628900D01*
G01Y-625033D02*
X1252700Y-624367D01*
X1253200Y-623833D01*
X1253900Y-623567D01*
X1254600Y-623833D01*
X1255100Y-624367D01*
X1255400Y-625167D01*
Y-628900D01*
G01X1258900Y-625300D02*
X1262100D01*
X1261800Y-624367D01*
X1261300Y-623833D01*
X1260600Y-623567D01*
X1259900Y-623700D01*
X1259300Y-624100D01*
X1258900Y-625033D01*
X1258700Y-625834D01*
Y-626633D01*
X1258900Y-627433D01*
X1259400Y-628233D01*
X1260000Y-628767D01*
X1260700Y-628900D01*
X1261400Y-628633D01*
X1262100Y-627834D01*
G01X1270000Y-624233D02*
X1269300Y-623700D01*
X1268700Y-623567D01*
X1267900Y-623833D01*
X1267300Y-624367D01*
X1266900Y-625300D01*
X1266800Y-626233D01*
X1266900Y-627167D01*
X1267300Y-627967D01*
X1267900Y-628633D01*
X1268700Y-628900D01*
X1269400Y-628633D01*
X1270000Y-628100D01*
G01X1274700Y-628900D02*
Y-620900D01*
G01Y-624767D02*
X1275200Y-624100D01*
X1275700Y-623700D01*
X1276500Y-623567D01*
X1277100Y-623700D01*
X1277800Y-624233D01*
X1278100Y-625033D01*
Y-628900D01*
G01X1286200D02*
Y-623567D01*
G01Y-624500D02*
X1285800Y-623967D01*
X1285200Y-623700D01*
X1284500Y-623567D01*
X1283800Y-623833D01*
X1283200Y-624367D01*
X1282800Y-625167D01*
X1282600Y-626233D01*
X1282800Y-627300D01*
X1283200Y-628100D01*
X1283800Y-628633D01*
X1284500Y-628900D01*
X1285200Y-628767D01*
X1285800Y-628367D01*
X1286200Y-627834D01*
G01X1290700Y-628900D02*
Y-623567D01*
G01Y-624900D02*
X1291100Y-624233D01*
X1291700Y-623700D01*
X1292500Y-623567D01*
X1293200Y-623700D01*
X1293800Y-624233D01*
X1294100Y-625167D01*
Y-628900D01*
G01X1300400Y-623567D02*
Y-628900D01*
G01Y-621433D02*
X1300200Y-621300D01*
Y-621033D01*
X1300400Y-620900D01*
X1300600Y-621033D01*
Y-621300D01*
X1300400Y-621433D01*
G01X1310000Y-624233D02*
X1309300Y-623700D01*
X1308700Y-623567D01*
X1307900Y-623833D01*
X1307300Y-624367D01*
X1306900Y-625300D01*
X1306800Y-626233D01*
X1306900Y-627167D01*
X1307300Y-627967D01*
X1307900Y-628633D01*
X1308700Y-628900D01*
X1309400Y-628633D01*
X1310000Y-628100D01*
G01X1318200Y-628900D02*
Y-623567D01*
G01Y-624500D02*
X1317800Y-623967D01*
X1317200Y-623700D01*
X1316500Y-623567D01*
X1315800Y-623833D01*
X1315200Y-624367D01*
X1314800Y-625167D01*
X1314600Y-626233D01*
X1314800Y-627300D01*
X1315200Y-628100D01*
X1315800Y-628633D01*
X1316500Y-628900D01*
X1317200Y-628767D01*
X1317800Y-628367D01*
X1318200Y-627834D01*
G01X1324400Y-628900D02*
Y-620900D01*
G01X1342200D02*
Y-628900D01*
G01Y-627700D02*
X1341800Y-628367D01*
X1341200Y-628767D01*
X1340500Y-628900D01*
X1339700Y-628633D01*
X1339100Y-627967D01*
X1338700Y-627167D01*
X1338600Y-626233D01*
X1338700Y-625300D01*
X1339100Y-624500D01*
X1339700Y-623833D01*
X1340500Y-623567D01*
X1341200Y-623700D01*
X1341700Y-623967D01*
X1342200Y-624500D01*
G01X1347000Y-628900D02*
Y-623567D01*
G01Y-624633D02*
X1347500Y-624100D01*
X1348000Y-623700D01*
X1348700Y-623567D01*
X1349200Y-623700D01*
X1349800Y-624100D01*
G01X1358200Y-628900D02*
Y-623567D01*
G01Y-624500D02*
X1357800Y-623967D01*
X1357200Y-623700D01*
X1356500Y-623567D01*
X1355800Y-623833D01*
X1355200Y-624367D01*
X1354800Y-625167D01*
X1354600Y-626233D01*
X1354800Y-627300D01*
X1355200Y-628100D01*
X1355800Y-628633D01*
X1356500Y-628900D01*
X1357200Y-628767D01*
X1357800Y-628367D01*
X1358200Y-627834D01*
G01X1361900Y-623567D02*
X1363100Y-628900D01*
X1364400Y-623567D01*
X1365700Y-628900D01*
X1366900Y-623567D01*
G01X1372400D02*
Y-628900D01*
G01Y-621433D02*
X1372200Y-621300D01*
Y-621033D01*
X1372400Y-620900D01*
X1372600Y-621033D01*
Y-621300D01*
X1372400Y-621433D01*
G01X1378700Y-628900D02*
Y-623567D01*
G01Y-624900D02*
X1379100Y-624233D01*
X1379700Y-623700D01*
X1380500Y-623567D01*
X1381200Y-623700D01*
X1381800Y-624233D01*
X1382100Y-625167D01*
Y-628900D01*
G01X1387000Y-630900D02*
X1387700Y-631433D01*
X1388500Y-631567D01*
X1389200Y-631433D01*
X1389800Y-630767D01*
X1390200Y-629833D01*
Y-623567D01*
G01Y-624633D02*
X1389800Y-624100D01*
X1389200Y-623700D01*
X1388500Y-623567D01*
X1387700Y-623833D01*
X1387200Y-624367D01*
X1386800Y-625300D01*
X1386600Y-626233D01*
X1386700Y-627033D01*
X1387100Y-627967D01*
X1387700Y-628633D01*
X1388500Y-628900D01*
X1389100Y-628767D01*
X1389800Y-628233D01*
X1390200Y-627700D01*
G01X1395700Y-631300D02*
X1397100Y-629433D01*
Y-627567D01*
X1395700D01*
Y-629433D01*
X1397100D01*
G01Y-626233D02*
Y-624367D01*
X1395700D01*
Y-626233D01*
X1397100D01*
G01X530000Y-609100D02*
Y-614833D01*
X530400Y-616034D01*
X531200Y-616833D01*
X532200Y-617100D01*
X533200Y-616833D01*
X534000Y-616034D01*
X534400Y-614833D01*
Y-609100D01*
G01X538500Y-617100D02*
Y-611767D01*
G01Y-613100D02*
X538900Y-612433D01*
X539500Y-611900D01*
X540300Y-611767D01*
X541000Y-611900D01*
X541600Y-612433D01*
X541900Y-613367D01*
Y-617100D01*
G01X548200Y-611767D02*
Y-617100D01*
G01Y-609633D02*
X548000Y-609500D01*
Y-609233D01*
X548200Y-609100D01*
X548400Y-609233D01*
Y-609500D01*
X548200Y-609633D01*
G01X556200Y-609100D02*
Y-617100D01*
G01X554800Y-611767D02*
X557600D01*
G01X573800Y-612433D02*
X573100Y-611900D01*
X572500Y-611767D01*
X571700Y-612033D01*
X571100Y-612567D01*
X570700Y-613500D01*
X570600Y-614433D01*
X570700Y-615367D01*
X571100Y-616167D01*
X571700Y-616833D01*
X572500Y-617100D01*
X573200Y-616833D01*
X573800Y-616300D01*
G01X580200Y-617100D02*
X579600Y-616967D01*
X579000Y-616433D01*
X578600Y-615500D01*
X578400Y-614433D01*
X578600Y-613367D01*
X579000Y-612433D01*
X579600Y-611900D01*
X580200Y-611767D01*
X580800Y-611900D01*
X581400Y-612433D01*
X581800Y-613367D01*
X581900Y-614433D01*
X581800Y-615500D01*
X581400Y-616433D01*
X580800Y-616967D01*
X580200Y-617100D01*
G01X586500D02*
Y-611767D01*
G01Y-613100D02*
X586900Y-612433D01*
X587500Y-611900D01*
X588300Y-611767D01*
X589000Y-611900D01*
X589600Y-612433D01*
X589900Y-613367D01*
Y-617100D01*
G01X594400Y-611767D02*
X596200Y-617100D01*
X598000Y-611767D01*
G01X602700Y-613500D02*
X605900D01*
X605600Y-612567D01*
X605100Y-612033D01*
X604400Y-611767D01*
X603700Y-611900D01*
X603100Y-612300D01*
X602700Y-613233D01*
X602500Y-614034D01*
Y-614833D01*
X602700Y-615633D01*
X603200Y-616433D01*
X603800Y-616967D01*
X604500Y-617100D01*
X605200Y-616833D01*
X605900Y-616034D01*
G01X610800Y-617100D02*
Y-611767D01*
G01Y-612833D02*
X611300Y-612300D01*
X611800Y-611900D01*
X612500Y-611767D01*
X613000Y-611900D01*
X613600Y-612300D01*
G01X618700Y-616167D02*
X619200Y-616700D01*
X619900Y-617100D01*
X620500D01*
X621100Y-616833D01*
X621500Y-616433D01*
X621700Y-615900D01*
X621600Y-615100D01*
X621200Y-614700D01*
X619400Y-613900D01*
X619000Y-612967D01*
X619200Y-612300D01*
X619600Y-611900D01*
X620200Y-611767D01*
X620800Y-611900D01*
X621400Y-612300D01*
G01X628200Y-611767D02*
Y-617100D01*
G01Y-609633D02*
X628000Y-609500D01*
Y-609233D01*
X628200Y-609100D01*
X628400Y-609233D01*
Y-609500D01*
X628200Y-609633D01*
G01X636200Y-617100D02*
X635600Y-616967D01*
X635000Y-616433D01*
X634600Y-615500D01*
X634400Y-614433D01*
X634600Y-613367D01*
X635000Y-612433D01*
X635600Y-611900D01*
X636200Y-611767D01*
X636800Y-611900D01*
X637400Y-612433D01*
X637800Y-613367D01*
X637900Y-614433D01*
X637800Y-615500D01*
X637400Y-616433D01*
X636800Y-616967D01*
X636200Y-617100D01*
G01X642500D02*
Y-611767D01*
G01Y-613100D02*
X642900Y-612433D01*
X643500Y-611900D01*
X644300Y-611767D01*
X645000Y-611900D01*
X645600Y-612433D01*
X645900Y-613367D01*
Y-617100D01*
G01X660200Y-611767D02*
Y-617100D01*
G01Y-609633D02*
X660000Y-609500D01*
Y-609233D01*
X660200Y-609100D01*
X660400Y-609233D01*
Y-609500D01*
X660200Y-609633D01*
G01X666700Y-616167D02*
X667200Y-616700D01*
X667900Y-617100D01*
X668500D01*
X669100Y-616833D01*
X669500Y-616433D01*
X669700Y-615900D01*
X669600Y-615100D01*
X669200Y-614700D01*
X667400Y-613900D01*
X667000Y-612967D01*
X667200Y-612300D01*
X667600Y-611900D01*
X668200Y-611767D01*
X668800Y-611900D01*
X669400Y-612300D01*
G01X674700Y-616167D02*
X675200Y-616700D01*
X675900Y-617100D01*
X676500D01*
X677100Y-616833D01*
X677500Y-616433D01*
X677700Y-615900D01*
X677600Y-615100D01*
X677200Y-614700D01*
X675400Y-613900D01*
X675000Y-612967D01*
X675200Y-612300D01*
X675600Y-611900D01*
X676200Y-611767D01*
X676800Y-611900D01*
X677400Y-612300D01*
G01X682500Y-611767D02*
Y-615500D01*
X682900Y-616433D01*
X683500Y-616967D01*
X684200Y-617100D01*
X684900Y-616967D01*
X685500Y-616433D01*
X685900Y-615500D01*
G01Y-617100D02*
Y-611767D01*
G01X690700Y-613500D02*
X693900D01*
X693600Y-612567D01*
X693100Y-612033D01*
X692400Y-611767D01*
X691700Y-611900D01*
X691100Y-612300D01*
X690700Y-613233D01*
X690500Y-614034D01*
Y-614833D01*
X690700Y-615633D01*
X691200Y-616433D01*
X691800Y-616967D01*
X692500Y-617100D01*
X693200Y-616833D01*
X693900Y-616034D01*
G01X700200Y-617367D02*
X700000Y-617233D01*
Y-616967D01*
X700200Y-616833D01*
X700400Y-616967D01*
Y-617233D01*
X700200Y-617367D01*
G01Y-613767D02*
X700000Y-613633D01*
Y-613367D01*
X700200Y-613233D01*
X700400Y-613367D01*
Y-613633D01*
X700200Y-613767D01*
G01X536200Y-577700D02*
Y-569700D01*
X535000Y-571300D01*
G01Y-577700D02*
X537400D01*
G01X544200D02*
Y-569700D01*
X543000Y-571300D01*
G01Y-577700D02*
X545400D01*
G01X535700Y-565200D02*
Y-557200D01*
X534500Y-558800D01*
G01Y-565200D02*
X536900D01*
G01X543700Y-557200D02*
X542900Y-557467D01*
X542300Y-558133D01*
X541900Y-558933D01*
X541600Y-560000D01*
X541500Y-561200D01*
X541600Y-562400D01*
X541900Y-563467D01*
X542300Y-564267D01*
X542900Y-564933D01*
X543700Y-565200D01*
X544500Y-564933D01*
X545100Y-564267D01*
X545500Y-563467D01*
X545800Y-562400D01*
X545900Y-561200D01*
X545800Y-560000D01*
X545500Y-558933D01*
X545100Y-558133D01*
X544500Y-557467D01*
X543700Y-557200D01*
G01X538500Y-551267D02*
X539200Y-551933D01*
X540000Y-552200D01*
X540800Y-551933D01*
X541500Y-551134D01*
X542000Y-549933D01*
X542200Y-548733D01*
Y-547267D01*
X542000Y-546067D01*
X541500Y-545000D01*
X540900Y-544467D01*
X540200Y-544200D01*
X539400Y-544467D01*
X538800Y-545000D01*
X538400Y-545800D01*
X538200Y-546867D01*
X538400Y-547800D01*
X538900Y-548733D01*
X539500Y-549267D01*
X540200Y-549400D01*
X541000Y-549134D01*
X541600Y-548467D01*
X542200Y-547267D01*
G01X540000Y-527700D02*
X540200Y-525967D01*
X540500Y-524500D01*
X540900Y-523167D01*
X541400Y-521700D01*
X542200Y-519700D01*
X538200D01*
G01X540200Y-539700D02*
X540900Y-539567D01*
X541700Y-539167D01*
X542200Y-538500D01*
X542400Y-537567D01*
X542200Y-536634D01*
X541600Y-535833D01*
X540700Y-535433D01*
X539700D01*
X539100Y-535167D01*
X538600Y-534500D01*
X538400Y-533567D01*
X538700Y-532633D01*
X539400Y-531967D01*
X540200Y-531700D01*
X541000Y-531967D01*
X541700Y-532633D01*
X542000Y-533567D01*
X541800Y-534500D01*
X541300Y-535167D01*
X540700Y-535433D01*
X539700D01*
X538800Y-535833D01*
X538200Y-536634D01*
X538000Y-537567D01*
X538200Y-538500D01*
X538700Y-539167D01*
X539500Y-539567D01*
X540200Y-539700D01*
G01X573200Y-577200D02*
Y-569200D01*
X575700D01*
X576500Y-569600D01*
X577000Y-570133D01*
X577200Y-571200D01*
X577000Y-572267D01*
X576400Y-572933D01*
X575700Y-573333D01*
X573200D01*
G01X575700D02*
X577200Y-577200D01*
G01X583200D02*
X582600Y-577067D01*
X582000Y-576533D01*
X581600Y-575600D01*
X581400Y-574533D01*
X581600Y-573467D01*
X582000Y-572533D01*
X582600Y-572000D01*
X583200Y-571867D01*
X583800Y-572000D01*
X584400Y-572533D01*
X584800Y-573467D01*
X584900Y-574533D01*
X584800Y-575600D01*
X584400Y-576533D01*
X583800Y-577067D01*
X583200Y-577200D01*
G01X589500Y-571867D02*
Y-575600D01*
X589900Y-576533D01*
X590500Y-577067D01*
X591200Y-577200D01*
X591900Y-577067D01*
X592500Y-576533D01*
X592900Y-575600D01*
G01Y-577200D02*
Y-571867D01*
G01X597800Y-579200D02*
X598500Y-579733D01*
X599300Y-579867D01*
X600000Y-579733D01*
X600600Y-579067D01*
X601000Y-578133D01*
Y-571867D01*
G01Y-572933D02*
X600600Y-572400D01*
X600000Y-572000D01*
X599300Y-571867D01*
X598500Y-572133D01*
X598000Y-572667D01*
X597600Y-573600D01*
X597400Y-574533D01*
X597500Y-575333D01*
X597900Y-576267D01*
X598500Y-576933D01*
X599300Y-577200D01*
X599900Y-577067D01*
X600600Y-576533D01*
X601000Y-576000D01*
G01X605500Y-577200D02*
Y-569200D01*
G01Y-573067D02*
X606000Y-572400D01*
X606500Y-572000D01*
X607300Y-571867D01*
X607900Y-572000D01*
X608600Y-572533D01*
X608900Y-573333D01*
Y-577200D01*
G01X613500D02*
Y-571867D01*
G01Y-573200D02*
X613900Y-572533D01*
X614500Y-572000D01*
X615300Y-571867D01*
X616000Y-572000D01*
X616600Y-572533D01*
X616900Y-573467D01*
Y-577200D01*
G01X621700Y-573600D02*
X624900D01*
X624600Y-572667D01*
X624100Y-572133D01*
X623400Y-571867D01*
X622700Y-572000D01*
X622100Y-572400D01*
X621700Y-573333D01*
X621500Y-574134D01*
Y-574933D01*
X621700Y-575733D01*
X622200Y-576533D01*
X622800Y-577067D01*
X623500Y-577200D01*
X624200Y-576933D01*
X624900Y-576134D01*
G01X629700Y-576267D02*
X630200Y-576800D01*
X630900Y-577200D01*
X631500D01*
X632100Y-576933D01*
X632500Y-576533D01*
X632700Y-576000D01*
X632600Y-575200D01*
X632200Y-574800D01*
X630400Y-574000D01*
X630000Y-573067D01*
X630200Y-572400D01*
X630600Y-572000D01*
X631200Y-571867D01*
X631800Y-572000D01*
X632400Y-572400D01*
G01X637700Y-576267D02*
X638200Y-576800D01*
X638900Y-577200D01*
X639500D01*
X640100Y-576933D01*
X640500Y-576533D01*
X640700Y-576000D01*
X640600Y-575200D01*
X640200Y-574800D01*
X638400Y-574000D01*
X638000Y-573067D01*
X638200Y-572400D01*
X638600Y-572000D01*
X639200Y-571867D01*
X639800Y-572000D01*
X640400Y-572400D01*
G01X538800Y-511367D02*
X539500Y-510433D01*
X540100Y-509900D01*
X540900Y-509633D01*
X541600Y-509900D01*
X542100Y-510433D01*
X542500Y-511233D01*
X542600Y-512167D01*
X542500Y-512967D01*
X542100Y-513767D01*
X541500Y-514433D01*
X540800Y-514700D01*
X540000Y-514433D01*
X539300Y-513634D01*
X538900Y-512433D01*
X538800Y-511100D01*
X539000Y-509367D01*
X539300Y-508433D01*
X539800Y-507500D01*
X540500Y-506833D01*
X541200Y-506700D01*
X541900Y-506967D01*
X542400Y-507633D01*
G01X541900Y-476700D02*
Y-468700D01*
X538200Y-474433D01*
X543200D01*
G01X538500Y-494000D02*
X539100Y-494667D01*
X539800Y-495067D01*
X540700Y-495200D01*
X541600Y-494933D01*
X542300Y-494400D01*
X542800Y-493467D01*
X542900Y-492400D01*
X542700Y-491333D01*
X542200Y-490667D01*
X541500Y-490133D01*
X540800Y-490000D01*
X540100Y-490133D01*
X539200Y-490667D01*
X539500Y-487200D01*
X542200D01*
G01X569600Y-485200D02*
Y-477200D01*
G01X573800D02*
Y-485200D01*
G01Y-481200D02*
X569600D01*
G01X579700Y-485200D02*
X579100Y-485067D01*
X578500Y-484533D01*
X578100Y-483600D01*
X577900Y-482533D01*
X578100Y-481467D01*
X578500Y-480533D01*
X579100Y-480000D01*
X579700Y-479867D01*
X580300Y-480000D01*
X580900Y-480533D01*
X581300Y-481467D01*
X581400Y-482533D01*
X581300Y-483600D01*
X580900Y-484533D01*
X580300Y-485067D01*
X579700Y-485200D01*
G01X587700D02*
Y-477200D01*
G01X594200Y-481600D02*
X597400D01*
X597100Y-480667D01*
X596600Y-480133D01*
X595900Y-479867D01*
X595200Y-480000D01*
X594600Y-480400D01*
X594200Y-481333D01*
X594000Y-482134D01*
Y-482933D01*
X594200Y-483733D01*
X594700Y-484533D01*
X595300Y-485067D01*
X596000Y-485200D01*
X596700Y-484933D01*
X597400Y-484134D01*
G01X538500Y-451100D02*
X539100Y-452033D01*
X539900Y-452567D01*
X540800Y-452700D01*
X541600Y-452567D01*
X542400Y-451900D01*
X542900Y-451100D01*
X543000Y-450300D01*
X542800Y-449367D01*
X542100Y-448700D01*
X541400Y-448433D01*
X540500D01*
G01X541400D02*
X542000Y-448033D01*
X542500Y-447367D01*
X542700Y-446567D01*
X542500Y-445767D01*
X542000Y-445100D01*
X541100Y-444700D01*
X540200Y-444833D01*
X539300Y-445367D01*
G01Y-433033D02*
X539900Y-432233D01*
X540600Y-431833D01*
X541400Y-431700D01*
X542400Y-431967D01*
X543100Y-432633D01*
X543300Y-433433D01*
X543200Y-434234D01*
X542800Y-434900D01*
X540800Y-436233D01*
X539900Y-437167D01*
X539300Y-438500D01*
X539100Y-439700D01*
X543300D01*
G01X541200Y-427200D02*
Y-419200D01*
X540000Y-420800D01*
G01Y-427200D02*
X542400D01*
G01X531400Y-411700D02*
Y-403700D01*
X536000Y-411700D01*
Y-403700D01*
G01X541700Y-411700D02*
X540900Y-411567D01*
X540200Y-411033D01*
X539600Y-410233D01*
X539200Y-409300D01*
X539000Y-408233D01*
Y-407167D01*
X539200Y-406100D01*
X539600Y-405167D01*
X540200Y-404367D01*
X540900Y-403833D01*
X541700Y-403700D01*
X542500Y-403833D01*
X543200Y-404367D01*
X543800Y-405167D01*
X544200Y-406100D01*
X544400Y-407167D01*
Y-408233D01*
X544200Y-409300D01*
X543800Y-410233D01*
X543200Y-411033D01*
X542500Y-411567D01*
X541700Y-411700D01*
G01X549700Y-411967D02*
X549500Y-411833D01*
Y-411567D01*
X549700Y-411433D01*
X549900Y-411567D01*
Y-411833D01*
X549700Y-411967D01*
G01X557600Y-427700D02*
Y-419700D01*
G01X561800D02*
Y-427700D01*
G01Y-423700D02*
X557600D01*
G01X567700Y-427700D02*
X567100Y-427567D01*
X566500Y-427033D01*
X566100Y-426100D01*
X565900Y-425033D01*
X566100Y-423967D01*
X566500Y-423033D01*
X567100Y-422500D01*
X567700Y-422367D01*
X568300Y-422500D01*
X568900Y-423033D01*
X569300Y-423967D01*
X569400Y-425033D01*
X569300Y-426100D01*
X568900Y-427033D01*
X568300Y-427567D01*
X567700Y-427700D01*
G01X575700D02*
Y-419700D01*
G01X582200Y-424100D02*
X585400D01*
X585100Y-423167D01*
X584600Y-422633D01*
X583900Y-422367D01*
X583200Y-422500D01*
X582600Y-422900D01*
X582200Y-423833D01*
X582000Y-424634D01*
Y-425433D01*
X582200Y-426233D01*
X582700Y-427033D01*
X583300Y-427567D01*
X584000Y-427700D01*
X584700Y-427433D01*
X585400Y-426634D01*
G01X587900Y-667600D02*
Y-675600D01*
G01X585600Y-667600D02*
X590200D01*
G01X594200Y-675600D02*
Y-667600D01*
G01Y-671467D02*
X594700Y-670800D01*
X595200Y-670400D01*
X596000Y-670267D01*
X596600Y-670400D01*
X597300Y-670933D01*
X597600Y-671733D01*
Y-675600D01*
G01X602400Y-672000D02*
X605600D01*
X605300Y-671067D01*
X604800Y-670533D01*
X604100Y-670267D01*
X603400Y-670400D01*
X602800Y-670800D01*
X602400Y-671733D01*
X602200Y-672534D01*
Y-673333D01*
X602400Y-674133D01*
X602900Y-674933D01*
X603500Y-675467D01*
X604200Y-675600D01*
X604900Y-675333D01*
X605600Y-674534D01*
G01X610500Y-675600D02*
Y-670267D01*
G01Y-671333D02*
X611000Y-670800D01*
X611500Y-670400D01*
X612200Y-670267D01*
X612700Y-670400D01*
X613300Y-670800D01*
G01X618400Y-672000D02*
X621600D01*
X621300Y-671067D01*
X620800Y-670533D01*
X620100Y-670267D01*
X619400Y-670400D01*
X618800Y-670800D01*
X618400Y-671733D01*
X618200Y-672534D01*
Y-673333D01*
X618400Y-674133D01*
X618900Y-674933D01*
X619500Y-675467D01*
X620200Y-675600D01*
X620900Y-675333D01*
X621600Y-674534D01*
G01X627300Y-675600D02*
Y-668800D01*
X627500Y-668133D01*
X627900Y-667733D01*
X628500Y-667600D01*
X629100Y-667867D01*
X629400Y-668533D01*
G01X628200Y-670800D02*
X626200D01*
G01X635900Y-675600D02*
X635300Y-675467D01*
X634700Y-674933D01*
X634300Y-674000D01*
X634100Y-672933D01*
X634300Y-671867D01*
X634700Y-670933D01*
X635300Y-670400D01*
X635900Y-670267D01*
X636500Y-670400D01*
X637100Y-670933D01*
X637500Y-671867D01*
X637600Y-672933D01*
X637500Y-674000D01*
X637100Y-674933D01*
X636500Y-675467D01*
X635900Y-675600D01*
G01X642500D02*
Y-670267D01*
G01Y-671333D02*
X643000Y-670800D01*
X643500Y-670400D01*
X644200Y-670267D01*
X644700Y-670400D01*
X645300Y-670800D01*
G01X650400Y-672000D02*
X653600D01*
X653300Y-671067D01*
X652800Y-670533D01*
X652100Y-670267D01*
X651400Y-670400D01*
X650800Y-670800D01*
X650400Y-671733D01*
X650200Y-672534D01*
Y-673333D01*
X650400Y-674133D01*
X650900Y-674933D01*
X651500Y-675467D01*
X652200Y-675600D01*
X652900Y-675333D01*
X653600Y-674534D01*
G01X659700Y-677067D02*
X660100Y-675333D01*
G01X674100Y-678267D02*
Y-670267D01*
G01Y-671467D02*
X674600Y-670800D01*
X675100Y-670400D01*
X675900Y-670267D01*
X676600Y-670400D01*
X677300Y-671067D01*
X677600Y-672000D01*
X677700Y-672933D01*
X677600Y-673867D01*
X677300Y-674800D01*
X676700Y-675333D01*
X675900Y-675600D01*
X675200Y-675467D01*
X674500Y-675067D01*
X674100Y-674534D01*
G01X683900Y-675600D02*
Y-667600D01*
G01X690400Y-672000D02*
X693600D01*
X693300Y-671067D01*
X692800Y-670533D01*
X692100Y-670267D01*
X691400Y-670400D01*
X690800Y-670800D01*
X690400Y-671733D01*
X690200Y-672534D01*
Y-673333D01*
X690400Y-674133D01*
X690900Y-674933D01*
X691500Y-675467D01*
X692200Y-675600D01*
X692900Y-675333D01*
X693600Y-674534D01*
G01X701700Y-675600D02*
Y-670267D01*
G01Y-671200D02*
X701300Y-670667D01*
X700700Y-670400D01*
X700000Y-670267D01*
X699300Y-670533D01*
X698700Y-671067D01*
X698300Y-671867D01*
X698100Y-672933D01*
X698300Y-674000D01*
X698700Y-674800D01*
X699300Y-675333D01*
X700000Y-675600D01*
X700700Y-675467D01*
X701300Y-675067D01*
X701700Y-674534D01*
G01X706400Y-674667D02*
X706900Y-675200D01*
X707600Y-675600D01*
X708200D01*
X708800Y-675333D01*
X709200Y-674933D01*
X709400Y-674400D01*
X709300Y-673600D01*
X708900Y-673200D01*
X707100Y-672400D01*
X706700Y-671467D01*
X706900Y-670800D01*
X707300Y-670400D01*
X707900Y-670267D01*
X708500Y-670400D01*
X709100Y-670800D01*
G01X714400Y-672000D02*
X717600D01*
X717300Y-671067D01*
X716800Y-670533D01*
X716100Y-670267D01*
X715400Y-670400D01*
X714800Y-670800D01*
X714400Y-671733D01*
X714200Y-672534D01*
Y-673333D01*
X714400Y-674133D01*
X714900Y-674933D01*
X715500Y-675467D01*
X716200Y-675600D01*
X716900Y-675333D01*
X717600Y-674534D01*
G01X731300Y-675600D02*
Y-668800D01*
X731500Y-668133D01*
X731900Y-667733D01*
X732500Y-667600D01*
X733100Y-667867D01*
X733400Y-668533D01*
G01X732200Y-670800D02*
X730200D01*
G01X739900Y-675600D02*
X739300Y-675467D01*
X738700Y-674933D01*
X738300Y-674000D01*
X738100Y-672933D01*
X738300Y-671867D01*
X738700Y-670933D01*
X739300Y-670400D01*
X739900Y-670267D01*
X740500Y-670400D01*
X741100Y-670933D01*
X741500Y-671867D01*
X741600Y-672933D01*
X741500Y-674000D01*
X741100Y-674933D01*
X740500Y-675467D01*
X739900Y-675600D01*
G01X747900D02*
Y-667600D01*
G01X755900Y-675600D02*
Y-667600D01*
G01X763900Y-675600D02*
X763300Y-675467D01*
X762700Y-674933D01*
X762300Y-674000D01*
X762100Y-672933D01*
X762300Y-671867D01*
X762700Y-670933D01*
X763300Y-670400D01*
X763900Y-670267D01*
X764500Y-670400D01*
X765100Y-670933D01*
X765500Y-671867D01*
X765600Y-672933D01*
X765500Y-674000D01*
X765100Y-674933D01*
X764500Y-675467D01*
X763900Y-675600D01*
G01X769400Y-670267D02*
X770600Y-675600D01*
X771900Y-670267D01*
X773200Y-675600D01*
X774400Y-670267D01*
G01X785700Y-674000D02*
X786300Y-674933D01*
X787100Y-675467D01*
X788000Y-675600D01*
X788800Y-675467D01*
X789600Y-674800D01*
X790100Y-674000D01*
X790200Y-673200D01*
X790000Y-672267D01*
X789300Y-671600D01*
X788600Y-671333D01*
X787700D01*
G01X788600D02*
X789200Y-670933D01*
X789700Y-670267D01*
X789900Y-669467D01*
X789700Y-668667D01*
X789200Y-668000D01*
X788300Y-667600D01*
X787400Y-667733D01*
X786500Y-668267D01*
G01X795900Y-675867D02*
X795700Y-675733D01*
Y-675467D01*
X795900Y-675333D01*
X796100Y-675467D01*
Y-675733D01*
X795900Y-675867D01*
G01X803900Y-675600D02*
Y-667600D01*
X802700Y-669200D01*
G01Y-675600D02*
X805100D01*
G01X811900D02*
X812600Y-675467D01*
X813400Y-675067D01*
X813900Y-674400D01*
X814100Y-673467D01*
X813900Y-672534D01*
X813300Y-671733D01*
X812400Y-671333D01*
X811400D01*
X810800Y-671067D01*
X810300Y-670400D01*
X810100Y-669467D01*
X810400Y-668533D01*
X811100Y-667867D01*
X811900Y-667600D01*
X812700Y-667867D01*
X813400Y-668533D01*
X813700Y-669467D01*
X813500Y-670400D01*
X813000Y-671067D01*
X812400Y-671333D01*
X811400D01*
X810500Y-671733D01*
X809900Y-672534D01*
X809700Y-673467D01*
X809900Y-674400D01*
X810400Y-675067D01*
X811200Y-675467D01*
X811900Y-675600D01*
G01X816900D02*
Y-670267D01*
G01Y-671733D02*
X817200Y-671067D01*
X817700Y-670533D01*
X818400Y-670267D01*
X819100Y-670533D01*
X819600Y-671067D01*
X819900Y-671733D01*
Y-675600D01*
G01Y-671733D02*
X820200Y-671067D01*
X820700Y-670533D01*
X821400Y-670267D01*
X822100Y-670533D01*
X822600Y-671067D01*
X822900Y-671867D01*
Y-675600D01*
G01X824900D02*
Y-670267D01*
G01Y-671733D02*
X825200Y-671067D01*
X825700Y-670533D01*
X826400Y-670267D01*
X827100Y-670533D01*
X827600Y-671067D01*
X827900Y-671733D01*
Y-675600D01*
G01Y-671733D02*
X828200Y-671067D01*
X828700Y-670533D01*
X829400Y-670267D01*
X830100Y-670533D01*
X830600Y-671067D01*
X830900Y-671867D01*
Y-675600D01*
G01X843900Y-667600D02*
Y-675600D01*
G01X842500Y-670267D02*
X845300D01*
G01X851900Y-675600D02*
X851300Y-675467D01*
X850700Y-674933D01*
X850300Y-674000D01*
X850100Y-672933D01*
X850300Y-671867D01*
X850700Y-670933D01*
X851300Y-670400D01*
X851900Y-670267D01*
X852500Y-670400D01*
X853100Y-670933D01*
X853500Y-671867D01*
X853600Y-672933D01*
X853500Y-674000D01*
X853100Y-674933D01*
X852500Y-675467D01*
X851900Y-675600D01*
G01X866100Y-678267D02*
Y-670267D01*
G01Y-671467D02*
X866600Y-670800D01*
X867100Y-670400D01*
X867900Y-670267D01*
X868600Y-670400D01*
X869300Y-671067D01*
X869600Y-672000D01*
X869700Y-672933D01*
X869600Y-673867D01*
X869300Y-674800D01*
X868700Y-675333D01*
X867900Y-675600D01*
X867200Y-675467D01*
X866500Y-675067D01*
X866100Y-674534D01*
G01X874500Y-675600D02*
Y-670267D01*
G01Y-671333D02*
X875000Y-670800D01*
X875500Y-670400D01*
X876200Y-670267D01*
X876700Y-670400D01*
X877300Y-670800D01*
G01X883900Y-675600D02*
X883300Y-675467D01*
X882700Y-674933D01*
X882300Y-674000D01*
X882100Y-672933D01*
X882300Y-671867D01*
X882700Y-670933D01*
X883300Y-670400D01*
X883900Y-670267D01*
X884500Y-670400D01*
X885100Y-670933D01*
X885500Y-671867D01*
X885600Y-672933D01*
X885500Y-674000D01*
X885100Y-674933D01*
X884500Y-675467D01*
X883900Y-675600D01*
G01X893700Y-667600D02*
Y-675600D01*
G01Y-674400D02*
X893300Y-675067D01*
X892700Y-675467D01*
X892000Y-675600D01*
X891200Y-675333D01*
X890600Y-674667D01*
X890200Y-673867D01*
X890100Y-672933D01*
X890200Y-672000D01*
X890600Y-671200D01*
X891200Y-670533D01*
X892000Y-670267D01*
X892700Y-670400D01*
X893200Y-670667D01*
X893700Y-671200D01*
G01X898200Y-670267D02*
Y-674000D01*
X898600Y-674933D01*
X899200Y-675467D01*
X899900Y-675600D01*
X900600Y-675467D01*
X901200Y-674933D01*
X901600Y-674000D01*
G01Y-675600D02*
Y-670267D01*
G01X909500Y-670933D02*
X908800Y-670400D01*
X908200Y-670267D01*
X907400Y-670533D01*
X906800Y-671067D01*
X906400Y-672000D01*
X906300Y-672933D01*
X906400Y-673867D01*
X906800Y-674667D01*
X907400Y-675333D01*
X908200Y-675600D01*
X908900Y-675333D01*
X909500Y-674800D01*
G01X914400Y-672000D02*
X917600D01*
X917300Y-671067D01*
X916800Y-670533D01*
X916100Y-670267D01*
X915400Y-670400D01*
X914800Y-670800D01*
X914400Y-671733D01*
X914200Y-672534D01*
Y-673333D01*
X914400Y-674133D01*
X914900Y-674933D01*
X915500Y-675467D01*
X916200Y-675600D01*
X916900Y-675333D01*
X917600Y-674534D01*
G01X931900Y-667600D02*
Y-675600D01*
G01X930500Y-670267D02*
X933300D01*
G01X938200Y-675600D02*
Y-667600D01*
G01Y-671467D02*
X938700Y-670800D01*
X939200Y-670400D01*
X940000Y-670267D01*
X940600Y-670400D01*
X941300Y-670933D01*
X941600Y-671733D01*
Y-675600D01*
G01X947900Y-670267D02*
Y-675600D01*
G01Y-668133D02*
X947700Y-668000D01*
Y-667733D01*
X947900Y-667600D01*
X948100Y-667733D01*
Y-668000D01*
X947900Y-668133D01*
G01X954400Y-674667D02*
X954900Y-675200D01*
X955600Y-675600D01*
X956200D01*
X956800Y-675333D01*
X957200Y-674933D01*
X957400Y-674400D01*
X957300Y-673600D01*
X956900Y-673200D01*
X955100Y-672400D01*
X954700Y-671467D01*
X954900Y-670800D01*
X955300Y-670400D01*
X955900Y-670267D01*
X956500Y-670400D01*
X957100Y-670800D01*
G01X970100Y-675600D02*
Y-667600D01*
G01Y-671600D02*
X970600Y-670800D01*
X971200Y-670400D01*
X971800Y-670267D01*
X972700Y-670533D01*
X973300Y-671067D01*
X973700Y-672000D01*
Y-673067D01*
X973500Y-674133D01*
X973100Y-674933D01*
X972400Y-675467D01*
X971800Y-675600D01*
X971200Y-675467D01*
X970600Y-675067D01*
X970100Y-674400D01*
G01X979900Y-675600D02*
X979300Y-675467D01*
X978700Y-674933D01*
X978300Y-674000D01*
X978100Y-672933D01*
X978300Y-671867D01*
X978700Y-670933D01*
X979300Y-670400D01*
X979900Y-670267D01*
X980500Y-670400D01*
X981100Y-670933D01*
X981500Y-671867D01*
X981600Y-672933D01*
X981500Y-674000D01*
X981100Y-674933D01*
X980500Y-675467D01*
X979900Y-675600D01*
G01X989700D02*
Y-670267D01*
G01Y-671200D02*
X989300Y-670667D01*
X988700Y-670400D01*
X988000Y-670267D01*
X987300Y-670533D01*
X986700Y-671067D01*
X986300Y-671867D01*
X986100Y-672933D01*
X986300Y-674000D01*
X986700Y-674800D01*
X987300Y-675333D01*
X988000Y-675600D01*
X988700Y-675467D01*
X989300Y-675067D01*
X989700Y-674534D01*
G01X994500Y-675600D02*
Y-670267D01*
G01Y-671333D02*
X995000Y-670800D01*
X995500Y-670400D01*
X996200Y-670267D01*
X996700Y-670400D01*
X997300Y-670800D01*
G01X1005700Y-667600D02*
Y-675600D01*
G01Y-674400D02*
X1005300Y-675067D01*
X1004700Y-675467D01*
X1004000Y-675600D01*
X1003200Y-675333D01*
X1002600Y-674667D01*
X1002200Y-673867D01*
X1002100Y-672933D01*
X1002200Y-672000D01*
X1002600Y-671200D01*
X1003200Y-670533D01*
X1004000Y-670267D01*
X1004700Y-670400D01*
X1005200Y-670667D01*
X1005700Y-671200D01*
G01X1011900Y-675867D02*
X1011700Y-675733D01*
Y-675467D01*
X1011900Y-675333D01*
X1012100Y-675467D01*
Y-675733D01*
X1011900Y-675867D01*
G01X587700Y-657600D02*
Y-665600D01*
G01X585400Y-657600D02*
X590000D01*
G01X594000Y-665600D02*
Y-657600D01*
G01Y-661467D02*
X594500Y-660800D01*
X595000Y-660400D01*
X595800Y-660267D01*
X596400Y-660400D01*
X597100Y-660933D01*
X597400Y-661733D01*
Y-665600D01*
G01X602200Y-662000D02*
X605400D01*
X605100Y-661067D01*
X604600Y-660533D01*
X603900Y-660267D01*
X603200Y-660400D01*
X602600Y-660800D01*
X602200Y-661733D01*
X602000Y-662534D01*
Y-663333D01*
X602200Y-664133D01*
X602700Y-664933D01*
X603300Y-665467D01*
X604000Y-665600D01*
X604700Y-665333D01*
X605400Y-664534D01*
G01X610000Y-665600D02*
Y-660267D01*
G01Y-661600D02*
X610400Y-660933D01*
X611000Y-660400D01*
X611800Y-660267D01*
X612500Y-660400D01*
X613100Y-660933D01*
X613400Y-661867D01*
Y-665600D01*
G01X629300Y-660933D02*
X628600Y-660400D01*
X628000Y-660267D01*
X627200Y-660533D01*
X626600Y-661067D01*
X626200Y-662000D01*
X626100Y-662933D01*
X626200Y-663867D01*
X626600Y-664667D01*
X627200Y-665333D01*
X628000Y-665600D01*
X628700Y-665333D01*
X629300Y-664800D01*
G01X635700Y-665600D02*
X635100Y-665467D01*
X634500Y-664933D01*
X634100Y-664000D01*
X633900Y-662933D01*
X634100Y-661867D01*
X634500Y-660933D01*
X635100Y-660400D01*
X635700Y-660267D01*
X636300Y-660400D01*
X636900Y-660933D01*
X637300Y-661867D01*
X637400Y-662933D01*
X637300Y-664000D01*
X636900Y-664933D01*
X636300Y-665467D01*
X635700Y-665600D01*
G01X642000D02*
Y-660267D01*
G01Y-661600D02*
X642400Y-660933D01*
X643000Y-660400D01*
X643800Y-660267D01*
X644500Y-660400D01*
X645100Y-660933D01*
X645400Y-661867D01*
Y-665600D01*
G01X649900Y-660267D02*
X651700Y-665600D01*
X653500Y-660267D01*
G01X658200Y-662000D02*
X661400D01*
X661100Y-661067D01*
X660600Y-660533D01*
X659900Y-660267D01*
X659200Y-660400D01*
X658600Y-660800D01*
X658200Y-661733D01*
X658000Y-662534D01*
Y-663333D01*
X658200Y-664133D01*
X658700Y-664933D01*
X659300Y-665467D01*
X660000Y-665600D01*
X660700Y-665333D01*
X661400Y-664534D01*
G01X666300Y-665600D02*
Y-660267D01*
G01Y-661333D02*
X666800Y-660800D01*
X667300Y-660400D01*
X668000Y-660267D01*
X668500Y-660400D01*
X669100Y-660800D01*
G01X675700Y-657600D02*
Y-665600D01*
G01X674300Y-660267D02*
X677100D01*
G01X689500Y-664000D02*
X690100Y-664933D01*
X690900Y-665467D01*
X691800Y-665600D01*
X692600Y-665467D01*
X693400Y-664800D01*
X693900Y-664000D01*
X694000Y-663200D01*
X693800Y-662267D01*
X693100Y-661600D01*
X692400Y-661333D01*
X691500D01*
G01X692400D02*
X693000Y-660933D01*
X693500Y-660267D01*
X693700Y-659467D01*
X693500Y-658667D01*
X693000Y-658000D01*
X692100Y-657600D01*
X691200Y-657733D01*
X690300Y-658267D01*
G01X699700Y-665867D02*
X699500Y-665733D01*
Y-665467D01*
X699700Y-665333D01*
X699900Y-665467D01*
Y-665733D01*
X699700Y-665867D01*
G01X707700Y-665600D02*
Y-657600D01*
X706500Y-659200D01*
G01Y-665600D02*
X708900D01*
G01X715700D02*
X716400Y-665467D01*
X717200Y-665067D01*
X717700Y-664400D01*
X717900Y-663467D01*
X717700Y-662534D01*
X717100Y-661733D01*
X716200Y-661333D01*
X715200D01*
X714600Y-661067D01*
X714100Y-660400D01*
X713900Y-659467D01*
X714200Y-658533D01*
X714900Y-657867D01*
X715700Y-657600D01*
X716500Y-657867D01*
X717200Y-658533D01*
X717500Y-659467D01*
X717300Y-660400D01*
X716800Y-661067D01*
X716200Y-661333D01*
X715200D01*
X714300Y-661733D01*
X713700Y-662534D01*
X713500Y-663467D01*
X713700Y-664400D01*
X714200Y-665067D01*
X715000Y-665467D01*
X715700Y-665600D01*
G01X720700D02*
Y-660267D01*
G01Y-661733D02*
X721000Y-661067D01*
X721500Y-660533D01*
X722200Y-660267D01*
X722900Y-660533D01*
X723400Y-661067D01*
X723700Y-661733D01*
Y-665600D01*
G01Y-661733D02*
X724000Y-661067D01*
X724500Y-660533D01*
X725200Y-660267D01*
X725900Y-660533D01*
X726400Y-661067D01*
X726700Y-661867D01*
Y-665600D01*
G01X728700D02*
Y-660267D01*
G01Y-661733D02*
X729000Y-661067D01*
X729500Y-660533D01*
X730200Y-660267D01*
X730900Y-660533D01*
X731400Y-661067D01*
X731700Y-661733D01*
Y-665600D01*
G01Y-661733D02*
X732000Y-661067D01*
X732500Y-660533D01*
X733200Y-660267D01*
X733900Y-660533D01*
X734400Y-661067D01*
X734700Y-661867D01*
Y-665600D01*
G01X747700Y-660267D02*
Y-665600D01*
G01Y-658133D02*
X747500Y-658000D01*
Y-657733D01*
X747700Y-657600D01*
X747900Y-657733D01*
Y-658000D01*
X747700Y-658133D01*
G01X754000Y-665600D02*
Y-660267D01*
G01Y-661600D02*
X754400Y-660933D01*
X755000Y-660400D01*
X755800Y-660267D01*
X756500Y-660400D01*
X757100Y-660933D01*
X757400Y-661867D01*
Y-665600D01*
G01X763700Y-657600D02*
Y-665600D01*
G01X762300Y-660267D02*
X765100D01*
G01X771700Y-665600D02*
X771100Y-665467D01*
X770500Y-664933D01*
X770100Y-664000D01*
X769900Y-662933D01*
X770100Y-661867D01*
X770500Y-660933D01*
X771100Y-660400D01*
X771700Y-660267D01*
X772300Y-660400D01*
X772900Y-660933D01*
X773300Y-661867D01*
X773400Y-662933D01*
X773300Y-664000D01*
X772900Y-664933D01*
X772300Y-665467D01*
X771700Y-665600D01*
G01X787700D02*
Y-657600D01*
X786500Y-659200D01*
G01Y-665600D02*
X788900D01*
G01X793800Y-658933D02*
X794400Y-658133D01*
X795100Y-657733D01*
X795900Y-657600D01*
X796900Y-657867D01*
X797600Y-658533D01*
X797800Y-659333D01*
X797700Y-660134D01*
X797300Y-660800D01*
X795300Y-662133D01*
X794400Y-663067D01*
X793800Y-664400D01*
X793600Y-665600D01*
X797800D01*
G01X801500Y-664400D02*
X802100Y-665067D01*
X802800Y-665467D01*
X803700Y-665600D01*
X804600Y-665333D01*
X805300Y-664800D01*
X805800Y-663867D01*
X805900Y-662800D01*
X805700Y-661733D01*
X805200Y-661067D01*
X804500Y-660533D01*
X803800Y-660400D01*
X803100Y-660533D01*
X802200Y-661067D01*
X802500Y-657600D01*
X805200D01*
G01X811700Y-665867D02*
X811500Y-665733D01*
Y-665467D01*
X811700Y-665333D01*
X811900Y-665467D01*
Y-665733D01*
X811700Y-665867D01*
G01X819700Y-665600D02*
Y-657600D01*
X818500Y-659200D01*
G01Y-665600D02*
X820900D01*
G01X826000Y-664667D02*
X826700Y-665333D01*
X827500Y-665600D01*
X828300Y-665333D01*
X829000Y-664534D01*
X829500Y-663333D01*
X829700Y-662133D01*
Y-660667D01*
X829500Y-659467D01*
X829000Y-658400D01*
X828400Y-657867D01*
X827700Y-657600D01*
X826900Y-657867D01*
X826300Y-658400D01*
X825900Y-659200D01*
X825700Y-660267D01*
X825900Y-661200D01*
X826400Y-662133D01*
X827000Y-662667D01*
X827700Y-662800D01*
X828500Y-662534D01*
X829100Y-661867D01*
X829700Y-660667D01*
G01X833800Y-662267D02*
X834500Y-661333D01*
X835100Y-660800D01*
X835900Y-660533D01*
X836600Y-660800D01*
X837100Y-661333D01*
X837500Y-662133D01*
X837600Y-663067D01*
X837500Y-663867D01*
X837100Y-664667D01*
X836500Y-665333D01*
X835800Y-665600D01*
X835000Y-665333D01*
X834300Y-664534D01*
X833900Y-663333D01*
X833800Y-662000D01*
X834000Y-660267D01*
X834300Y-659333D01*
X834800Y-658400D01*
X835500Y-657733D01*
X836200Y-657600D01*
X836900Y-657867D01*
X837400Y-658533D01*
G01X843700Y-665600D02*
X844400Y-665467D01*
X845200Y-665067D01*
X845700Y-664400D01*
X845900Y-663467D01*
X845700Y-662534D01*
X845100Y-661733D01*
X844200Y-661333D01*
X843200D01*
X842600Y-661067D01*
X842100Y-660400D01*
X841900Y-659467D01*
X842200Y-658533D01*
X842900Y-657867D01*
X843700Y-657600D01*
X844500Y-657867D01*
X845200Y-658533D01*
X845500Y-659467D01*
X845300Y-660400D01*
X844800Y-661067D01*
X844200Y-661333D01*
X843200D01*
X842300Y-661733D01*
X841700Y-662534D01*
X841500Y-663467D01*
X841700Y-664400D01*
X842200Y-665067D01*
X843000Y-665467D01*
X843700Y-665600D01*
G01X848700D02*
Y-660267D01*
G01Y-661733D02*
X849000Y-661067D01*
X849500Y-660533D01*
X850200Y-660267D01*
X850900Y-660533D01*
X851400Y-661067D01*
X851700Y-661733D01*
Y-665600D01*
G01Y-661733D02*
X852000Y-661067D01*
X852500Y-660533D01*
X853200Y-660267D01*
X853900Y-660533D01*
X854400Y-661067D01*
X854700Y-661867D01*
Y-665600D01*
G01X859700Y-660267D02*
Y-665600D01*
G01Y-658133D02*
X859500Y-658000D01*
Y-657733D01*
X859700Y-657600D01*
X859900Y-657733D01*
Y-658000D01*
X859700Y-658133D01*
G01X867700Y-665600D02*
Y-657600D01*
G01X875500Y-667067D02*
X875900Y-665333D01*
G01X891700Y-657600D02*
Y-665600D01*
G01X890300Y-660267D02*
X893100D01*
G01X898000Y-665600D02*
Y-657600D01*
G01Y-661467D02*
X898500Y-660800D01*
X899000Y-660400D01*
X899800Y-660267D01*
X900400Y-660400D01*
X901100Y-660933D01*
X901400Y-661733D01*
Y-665600D01*
G01X906200Y-662000D02*
X909400D01*
X909100Y-661067D01*
X908600Y-660533D01*
X907900Y-660267D01*
X907200Y-660400D01*
X906600Y-660800D01*
X906200Y-661733D01*
X906000Y-662534D01*
Y-663333D01*
X906200Y-664133D01*
X906700Y-664933D01*
X907300Y-665467D01*
X908000Y-665600D01*
X908700Y-665333D01*
X909400Y-664534D01*
G01X925500Y-657600D02*
Y-665600D01*
G01Y-664400D02*
X925100Y-665067D01*
X924500Y-665467D01*
X923800Y-665600D01*
X923000Y-665333D01*
X922400Y-664667D01*
X922000Y-663867D01*
X921900Y-662933D01*
X922000Y-662000D01*
X922400Y-661200D01*
X923000Y-660533D01*
X923800Y-660267D01*
X924500Y-660400D01*
X925000Y-660667D01*
X925500Y-661200D01*
G01X931700Y-660267D02*
Y-665600D01*
G01Y-658133D02*
X931500Y-658000D01*
Y-657733D01*
X931700Y-657600D01*
X931900Y-657733D01*
Y-658000D01*
X931700Y-658133D01*
G01X939100Y-665600D02*
Y-658800D01*
X939300Y-658133D01*
X939700Y-657733D01*
X940300Y-657600D01*
X940900Y-657867D01*
X941200Y-658533D01*
G01X940000Y-660800D02*
X938000D01*
G01X947100Y-665600D02*
Y-658800D01*
X947300Y-658133D01*
X947700Y-657733D01*
X948300Y-657600D01*
X948900Y-657867D01*
X949200Y-658533D01*
G01X948000Y-660800D02*
X946000D01*
G01X954200Y-662000D02*
X957400D01*
X957100Y-661067D01*
X956600Y-660533D01*
X955900Y-660267D01*
X955200Y-660400D01*
X954600Y-660800D01*
X954200Y-661733D01*
X954000Y-662534D01*
Y-663333D01*
X954200Y-664133D01*
X954700Y-664933D01*
X955300Y-665467D01*
X956000Y-665600D01*
X956700Y-665333D01*
X957400Y-664534D01*
G01X962300Y-665600D02*
Y-660267D01*
G01Y-661333D02*
X962800Y-660800D01*
X963300Y-660400D01*
X964000Y-660267D01*
X964500Y-660400D01*
X965100Y-660800D01*
G01X970200Y-662000D02*
X973400D01*
X973100Y-661067D01*
X972600Y-660533D01*
X971900Y-660267D01*
X971200Y-660400D01*
X970600Y-660800D01*
X970200Y-661733D01*
X970000Y-662534D01*
Y-663333D01*
X970200Y-664133D01*
X970700Y-664933D01*
X971300Y-665467D01*
X972000Y-665600D01*
X972700Y-665333D01*
X973400Y-664534D01*
G01X978000Y-665600D02*
Y-660267D01*
G01Y-661600D02*
X978400Y-660933D01*
X979000Y-660400D01*
X979800Y-660267D01*
X980500Y-660400D01*
X981100Y-660933D01*
X981400Y-661867D01*
Y-665600D01*
G01X989300Y-660933D02*
X988600Y-660400D01*
X988000Y-660267D01*
X987200Y-660533D01*
X986600Y-661067D01*
X986200Y-662000D01*
X986100Y-662933D01*
X986200Y-663867D01*
X986600Y-664667D01*
X987200Y-665333D01*
X988000Y-665600D01*
X988700Y-665333D01*
X989300Y-664800D01*
G01X994200Y-662000D02*
X997400D01*
X997100Y-661067D01*
X996600Y-660533D01*
X995900Y-660267D01*
X995200Y-660400D01*
X994600Y-660800D01*
X994200Y-661733D01*
X994000Y-662534D01*
Y-663333D01*
X994200Y-664133D01*
X994700Y-664933D01*
X995300Y-665467D01*
X996000Y-665600D01*
X996700Y-665333D01*
X997400Y-664534D01*
G01X1009900Y-665600D02*
Y-657600D01*
G01Y-661600D02*
X1010400Y-660800D01*
X1011000Y-660400D01*
X1011600Y-660267D01*
X1012500Y-660533D01*
X1013100Y-661067D01*
X1013500Y-662000D01*
Y-663067D01*
X1013300Y-664133D01*
X1012900Y-664933D01*
X1012200Y-665467D01*
X1011600Y-665600D01*
X1011000Y-665467D01*
X1010400Y-665067D01*
X1009900Y-664400D01*
G01X1018200Y-662000D02*
X1021400D01*
X1021100Y-661067D01*
X1020600Y-660533D01*
X1019900Y-660267D01*
X1019200Y-660400D01*
X1018600Y-660800D01*
X1018200Y-661733D01*
X1018000Y-662534D01*
Y-663333D01*
X1018200Y-664133D01*
X1018700Y-664933D01*
X1019300Y-665467D01*
X1020000Y-665600D01*
X1020700Y-665333D01*
X1021400Y-664534D01*
G01X1027700Y-657600D02*
Y-665600D01*
G01X1026300Y-660267D02*
X1029100D01*
G01X1033200D02*
X1034400Y-665600D01*
X1035700Y-660267D01*
X1037000Y-665600D01*
X1038200Y-660267D01*
G01X1042200Y-662000D02*
X1045400D01*
X1045100Y-661067D01*
X1044600Y-660533D01*
X1043900Y-660267D01*
X1043200Y-660400D01*
X1042600Y-660800D01*
X1042200Y-661733D01*
X1042000Y-662534D01*
Y-663333D01*
X1042200Y-664133D01*
X1042700Y-664933D01*
X1043300Y-665467D01*
X1044000Y-665600D01*
X1044700Y-665333D01*
X1045400Y-664534D01*
G01X1050200Y-662000D02*
X1053400D01*
X1053100Y-661067D01*
X1052600Y-660533D01*
X1051900Y-660267D01*
X1051200Y-660400D01*
X1050600Y-660800D01*
X1050200Y-661733D01*
X1050000Y-662534D01*
Y-663333D01*
X1050200Y-664133D01*
X1050700Y-664933D01*
X1051300Y-665467D01*
X1052000Y-665600D01*
X1052700Y-665333D01*
X1053400Y-664534D01*
G01X1058000Y-665600D02*
Y-660267D01*
G01Y-661600D02*
X1058400Y-660933D01*
X1059000Y-660400D01*
X1059800Y-660267D01*
X1060500Y-660400D01*
X1061100Y-660933D01*
X1061400Y-661867D01*
Y-665600D01*
G01X1075700D02*
Y-657600D01*
X1074500Y-659200D01*
G01Y-665600D02*
X1076900D01*
G01X1081800Y-658933D02*
X1082400Y-658133D01*
X1083100Y-657733D01*
X1083900Y-657600D01*
X1084900Y-657867D01*
X1085600Y-658533D01*
X1085800Y-659333D01*
X1085700Y-660134D01*
X1085300Y-660800D01*
X1083300Y-662133D01*
X1082400Y-663067D01*
X1081800Y-664400D01*
X1081600Y-665600D01*
X1085800D01*
G01X1089800Y-662267D02*
X1090500Y-661333D01*
X1091100Y-660800D01*
X1091900Y-660533D01*
X1092600Y-660800D01*
X1093100Y-661333D01*
X1093500Y-662133D01*
X1093600Y-663067D01*
X1093500Y-663867D01*
X1093100Y-664667D01*
X1092500Y-665333D01*
X1091800Y-665600D01*
X1091000Y-665333D01*
X1090300Y-664534D01*
X1089900Y-663333D01*
X1089800Y-662000D01*
X1090000Y-660267D01*
X1090300Y-659333D01*
X1090800Y-658400D01*
X1091500Y-657733D01*
X1092200Y-657600D01*
X1092900Y-657867D01*
X1093400Y-658533D01*
G01X1096700Y-665600D02*
Y-660267D01*
G01Y-661733D02*
X1097000Y-661067D01*
X1097500Y-660533D01*
X1098200Y-660267D01*
X1098900Y-660533D01*
X1099400Y-661067D01*
X1099700Y-661733D01*
Y-665600D01*
G01Y-661733D02*
X1100000Y-661067D01*
X1100500Y-660533D01*
X1101200Y-660267D01*
X1101900Y-660533D01*
X1102400Y-661067D01*
X1102700Y-661867D01*
Y-665600D01*
G01X1107700Y-660267D02*
Y-665600D01*
G01Y-658133D02*
X1107500Y-658000D01*
Y-657733D01*
X1107700Y-657600D01*
X1107900Y-657733D01*
Y-658000D01*
X1107700Y-658133D01*
G01X1115700Y-665600D02*
Y-657600D01*
G01X1133500Y-665600D02*
Y-660267D01*
G01Y-661200D02*
X1133100Y-660667D01*
X1132500Y-660400D01*
X1131800Y-660267D01*
X1131100Y-660533D01*
X1130500Y-661067D01*
X1130100Y-661867D01*
X1129900Y-662933D01*
X1130100Y-664000D01*
X1130500Y-664800D01*
X1131100Y-665333D01*
X1131800Y-665600D01*
X1132500Y-665467D01*
X1133100Y-665067D01*
X1133500Y-664534D01*
G01X1138000Y-665600D02*
Y-660267D01*
G01Y-661600D02*
X1138400Y-660933D01*
X1139000Y-660400D01*
X1139800Y-660267D01*
X1140500Y-660400D01*
X1141100Y-660933D01*
X1141400Y-661867D01*
Y-665600D01*
G01X1149500Y-657600D02*
Y-665600D01*
G01Y-664400D02*
X1149100Y-665067D01*
X1148500Y-665467D01*
X1147800Y-665600D01*
X1147000Y-665333D01*
X1146400Y-664667D01*
X1146000Y-663867D01*
X1145900Y-662933D01*
X1146000Y-662000D01*
X1146400Y-661200D01*
X1147000Y-660533D01*
X1147800Y-660267D01*
X1148500Y-660400D01*
X1149000Y-660667D01*
X1149500Y-661200D01*
G01X1163700Y-665600D02*
Y-657600D01*
X1162500Y-659200D01*
G01Y-665600D02*
X1164900D01*
G01X1169800Y-658933D02*
X1170400Y-658133D01*
X1171100Y-657733D01*
X1171900Y-657600D01*
X1172900Y-657867D01*
X1173600Y-658533D01*
X1173800Y-659333D01*
X1173700Y-660134D01*
X1173300Y-660800D01*
X1171300Y-662133D01*
X1170400Y-663067D01*
X1169800Y-664400D01*
X1169600Y-665600D01*
X1173800D01*
G01X1177500Y-664400D02*
X1178100Y-665067D01*
X1178800Y-665467D01*
X1179700Y-665600D01*
X1180600Y-665333D01*
X1181300Y-664800D01*
X1181800Y-663867D01*
X1181900Y-662800D01*
X1181700Y-661733D01*
X1181200Y-661067D01*
X1180500Y-660533D01*
X1179800Y-660400D01*
X1179100Y-660533D01*
X1178200Y-661067D01*
X1178500Y-657600D01*
X1181200D01*
G01X1187700Y-665867D02*
X1187500Y-665733D01*
Y-665467D01*
X1187700Y-665333D01*
X1187900Y-665467D01*
Y-665733D01*
X1187700Y-665867D01*
G01X1195700Y-665600D02*
Y-657600D01*
X1194500Y-659200D01*
G01Y-665600D02*
X1196900D01*
G01X1202000Y-664667D02*
X1202700Y-665333D01*
X1203500Y-665600D01*
X1204300Y-665333D01*
X1205000Y-664534D01*
X1205500Y-663333D01*
X1205700Y-662133D01*
Y-660667D01*
X1205500Y-659467D01*
X1205000Y-658400D01*
X1204400Y-657867D01*
X1203700Y-657600D01*
X1202900Y-657867D01*
X1202300Y-658400D01*
X1201900Y-659200D01*
X1201700Y-660267D01*
X1201900Y-661200D01*
X1202400Y-662133D01*
X1203000Y-662667D01*
X1203700Y-662800D01*
X1204500Y-662534D01*
X1205100Y-661867D01*
X1205700Y-660667D01*
G01X1209800Y-662267D02*
X1210500Y-661333D01*
X1211100Y-660800D01*
X1211900Y-660533D01*
X1212600Y-660800D01*
X1213100Y-661333D01*
X1213500Y-662133D01*
X1213600Y-663067D01*
X1213500Y-663867D01*
X1213100Y-664667D01*
X1212500Y-665333D01*
X1211800Y-665600D01*
X1211000Y-665333D01*
X1210300Y-664534D01*
X1209900Y-663333D01*
X1209800Y-662000D01*
X1210000Y-660267D01*
X1210300Y-659333D01*
X1210800Y-658400D01*
X1211500Y-657733D01*
X1212200Y-657600D01*
X1212900Y-657867D01*
X1213400Y-658533D01*
G01X1219700Y-665600D02*
X1220400Y-665467D01*
X1221200Y-665067D01*
X1221700Y-664400D01*
X1221900Y-663467D01*
X1221700Y-662534D01*
X1221100Y-661733D01*
X1220200Y-661333D01*
X1219200D01*
X1218600Y-661067D01*
X1218100Y-660400D01*
X1217900Y-659467D01*
X1218200Y-658533D01*
X1218900Y-657867D01*
X1219700Y-657600D01*
X1220500Y-657867D01*
X1221200Y-658533D01*
X1221500Y-659467D01*
X1221300Y-660400D01*
X1220800Y-661067D01*
X1220200Y-661333D01*
X1219200D01*
X1218300Y-661733D01*
X1217700Y-662534D01*
X1217500Y-663467D01*
X1217700Y-664400D01*
X1218200Y-665067D01*
X1219000Y-665467D01*
X1219700Y-665600D01*
G01X1235700Y-660267D02*
Y-665600D01*
G01Y-658133D02*
X1235500Y-658000D01*
Y-657733D01*
X1235700Y-657600D01*
X1235900Y-657733D01*
Y-658000D01*
X1235700Y-658133D01*
G01X1242200Y-664667D02*
X1242700Y-665200D01*
X1243400Y-665600D01*
X1244000D01*
X1244600Y-665333D01*
X1245000Y-664933D01*
X1245200Y-664400D01*
X1245100Y-663600D01*
X1244700Y-663200D01*
X1242900Y-662400D01*
X1242500Y-661467D01*
X1242700Y-660800D01*
X1243100Y-660400D01*
X1243700Y-660267D01*
X1244300Y-660400D01*
X1244900Y-660800D01*
G01X1259700Y-665600D02*
Y-657600D01*
G01X1266200Y-662000D02*
X1269400D01*
X1269100Y-661067D01*
X1268600Y-660533D01*
X1267900Y-660267D01*
X1267200Y-660400D01*
X1266600Y-660800D01*
X1266200Y-661733D01*
X1266000Y-662534D01*
Y-663333D01*
X1266200Y-664133D01*
X1266700Y-664933D01*
X1267300Y-665467D01*
X1268000Y-665600D01*
X1268700Y-665333D01*
X1269400Y-664534D01*
G01X1274200Y-664667D02*
X1274700Y-665200D01*
X1275400Y-665600D01*
X1276000D01*
X1276600Y-665333D01*
X1277000Y-664933D01*
X1277200Y-664400D01*
X1277100Y-663600D01*
X1276700Y-663200D01*
X1274900Y-662400D01*
X1274500Y-661467D01*
X1274700Y-660800D01*
X1275100Y-660400D01*
X1275700Y-660267D01*
X1276300Y-660400D01*
X1276900Y-660800D01*
G01X1282200Y-664667D02*
X1282700Y-665200D01*
X1283400Y-665600D01*
X1284000D01*
X1284600Y-665333D01*
X1285000Y-664933D01*
X1285200Y-664400D01*
X1285100Y-663600D01*
X1284700Y-663200D01*
X1282900Y-662400D01*
X1282500Y-661467D01*
X1282700Y-660800D01*
X1283100Y-660400D01*
X1283700Y-660267D01*
X1284300Y-660400D01*
X1284900Y-660800D01*
G01X1299700Y-657600D02*
Y-665600D01*
G01X1298300Y-660267D02*
X1301100D01*
G01X1306000Y-665600D02*
Y-657600D01*
G01Y-661467D02*
X1306500Y-660800D01*
X1307000Y-660400D01*
X1307800Y-660267D01*
X1308400Y-660400D01*
X1309100Y-660933D01*
X1309400Y-661733D01*
Y-665600D01*
G01X1317500D02*
Y-660267D01*
G01Y-661200D02*
X1317100Y-660667D01*
X1316500Y-660400D01*
X1315800Y-660267D01*
X1315100Y-660533D01*
X1314500Y-661067D01*
X1314100Y-661867D01*
X1313900Y-662933D01*
X1314100Y-664000D01*
X1314500Y-664800D01*
X1315100Y-665333D01*
X1315800Y-665600D01*
X1316500Y-665467D01*
X1317100Y-665067D01*
X1317500Y-664534D01*
G01X1322000Y-665600D02*
Y-660267D01*
G01Y-661600D02*
X1322400Y-660933D01*
X1323000Y-660400D01*
X1323800Y-660267D01*
X1324500Y-660400D01*
X1325100Y-660933D01*
X1325400Y-661867D01*
Y-665600D01*
G01X1339700D02*
Y-657600D01*
X1338500Y-659200D01*
G01Y-665600D02*
X1340900D01*
G01X1352700D02*
Y-660267D01*
G01Y-661733D02*
X1353000Y-661067D01*
X1353500Y-660533D01*
X1354200Y-660267D01*
X1354900Y-660533D01*
X1355400Y-661067D01*
X1355700Y-661733D01*
Y-665600D01*
G01Y-661733D02*
X1356000Y-661067D01*
X1356500Y-660533D01*
X1357200Y-660267D01*
X1357900Y-660533D01*
X1358400Y-661067D01*
X1358700Y-661867D01*
Y-665600D01*
G01X1363700Y-660267D02*
Y-665600D01*
G01Y-658133D02*
X1363500Y-658000D01*
Y-657733D01*
X1363700Y-657600D01*
X1363900Y-657733D01*
Y-658000D01*
X1363700Y-658133D01*
G01X1371700Y-665600D02*
Y-657600D01*
G01X1379500Y-667067D02*
X1379900Y-665333D01*
G01X612600Y-484134D02*
X613400Y-484800D01*
X614300Y-485200D01*
X615100D01*
X615900Y-484800D01*
X616500Y-484134D01*
X616800Y-483200D01*
X616600Y-482267D01*
X616100Y-481467D01*
X615200Y-480933D01*
X614000Y-480667D01*
X613300Y-480133D01*
X613000Y-479200D01*
X613200Y-478267D01*
X613700Y-477600D01*
X614400Y-477200D01*
X615100D01*
X615800Y-477467D01*
X616400Y-478133D01*
G01X622700Y-479867D02*
Y-485200D01*
G01Y-477733D02*
X622500Y-477600D01*
Y-477333D01*
X622700Y-477200D01*
X622900Y-477333D01*
Y-477600D01*
X622700Y-477733D01*
G01X629200Y-479867D02*
X632200D01*
X629200Y-485200D01*
X632200D01*
G01X637200Y-481600D02*
X640400D01*
X640100Y-480667D01*
X639600Y-480133D01*
X638900Y-479867D01*
X638200Y-480000D01*
X637600Y-480400D01*
X637200Y-481333D01*
X637000Y-482134D01*
Y-482933D01*
X637200Y-483733D01*
X637700Y-484533D01*
X638300Y-485067D01*
X639000Y-485200D01*
X639700Y-484933D01*
X640400Y-484134D01*
G01X592200Y-428200D02*
X594700Y-420200D01*
X597200Y-428200D01*
G01X596300Y-425400D02*
X593100D01*
G01X602700Y-428200D02*
Y-420200D01*
G01X610700Y-422867D02*
Y-428200D01*
G01Y-420733D02*
X610500Y-420600D01*
Y-420333D01*
X610700Y-420200D01*
X610900Y-420333D01*
Y-420600D01*
X610700Y-420733D01*
G01X617300Y-430200D02*
X618000Y-430733D01*
X618800Y-430867D01*
X619500Y-430733D01*
X620100Y-430067D01*
X620500Y-429133D01*
Y-422867D01*
G01Y-423933D02*
X620100Y-423400D01*
X619500Y-423000D01*
X618800Y-422867D01*
X618000Y-423133D01*
X617500Y-423667D01*
X617100Y-424600D01*
X616900Y-425533D01*
X617000Y-426333D01*
X617400Y-427267D01*
X618000Y-427933D01*
X618800Y-428200D01*
X619400Y-428067D01*
X620100Y-427533D01*
X620500Y-427000D01*
G01X625000Y-428200D02*
Y-422867D01*
G01Y-424200D02*
X625400Y-423533D01*
X626000Y-423000D01*
X626800Y-422867D01*
X627500Y-423000D01*
X628100Y-423533D01*
X628400Y-424467D01*
Y-428200D01*
G01X631700D02*
Y-422867D01*
G01Y-424333D02*
X632000Y-423667D01*
X632500Y-423133D01*
X633200Y-422867D01*
X633900Y-423133D01*
X634400Y-423667D01*
X634700Y-424333D01*
Y-428200D01*
G01Y-424333D02*
X635000Y-423667D01*
X635500Y-423133D01*
X636200Y-422867D01*
X636900Y-423133D01*
X637400Y-423667D01*
X637700Y-424467D01*
Y-428200D01*
G01X641200Y-424600D02*
X644400D01*
X644100Y-423667D01*
X643600Y-423133D01*
X642900Y-422867D01*
X642200Y-423000D01*
X641600Y-423400D01*
X641200Y-424333D01*
X641000Y-425134D01*
Y-425933D01*
X641200Y-426733D01*
X641700Y-427533D01*
X642300Y-428067D01*
X643000Y-428200D01*
X643700Y-427933D01*
X644400Y-427134D01*
G01X649000Y-428200D02*
Y-422867D01*
G01Y-424200D02*
X649400Y-423533D01*
X650000Y-423000D01*
X650800Y-422867D01*
X651500Y-423000D01*
X652100Y-423533D01*
X652400Y-424467D01*
Y-428200D01*
G01X658700Y-420200D02*
Y-428200D01*
G01X657300Y-422867D02*
X660100D01*
G01X675100Y-576700D02*
Y-568700D01*
G01X679300D02*
Y-576700D01*
G01Y-572700D02*
X675100D01*
G01X685200Y-576700D02*
X684600Y-576567D01*
X684000Y-576033D01*
X683600Y-575100D01*
X683400Y-574033D01*
X683600Y-572967D01*
X684000Y-572033D01*
X684600Y-571500D01*
X685200Y-571367D01*
X685800Y-571500D01*
X686400Y-572033D01*
X686800Y-572967D01*
X686900Y-574033D01*
X686800Y-575100D01*
X686400Y-576033D01*
X685800Y-576567D01*
X685200Y-576700D01*
G01X693200D02*
Y-568700D01*
G01X699700Y-573100D02*
X702900D01*
X702600Y-572167D01*
X702100Y-571633D01*
X701400Y-571367D01*
X700700Y-571500D01*
X700100Y-571900D01*
X699700Y-572833D01*
X699500Y-573634D01*
Y-574433D01*
X699700Y-575233D01*
X700200Y-576033D01*
X700800Y-576567D01*
X701500Y-576700D01*
X702200Y-576433D01*
X702900Y-575634D01*
G01X714200Y-568700D02*
X715600Y-576700D01*
X717200Y-568700D01*
X718800Y-576700D01*
X720200Y-568700D01*
G01X727000Y-576700D02*
Y-571367D01*
G01Y-572300D02*
X726600Y-571767D01*
X726000Y-571500D01*
X725300Y-571367D01*
X724600Y-571633D01*
X724000Y-572167D01*
X723600Y-572967D01*
X723400Y-574033D01*
X723600Y-575100D01*
X724000Y-575900D01*
X724600Y-576433D01*
X725300Y-576700D01*
X726000Y-576567D01*
X726600Y-576167D01*
X727000Y-575634D01*
G01X733200Y-576700D02*
Y-568700D01*
G01X741200Y-576700D02*
Y-568700D01*
G01X755200Y-576700D02*
Y-568700D01*
X757700D01*
X758500Y-569100D01*
X759000Y-569633D01*
X759200Y-570700D01*
X759000Y-571767D01*
X758400Y-572433D01*
X757700Y-572833D01*
X755200D01*
G01X757700D02*
X759200Y-576700D01*
G01X765200D02*
X764600Y-576567D01*
X764000Y-576033D01*
X763600Y-575100D01*
X763400Y-574033D01*
X763600Y-572967D01*
X764000Y-572033D01*
X764600Y-571500D01*
X765200Y-571367D01*
X765800Y-571500D01*
X766400Y-572033D01*
X766800Y-572967D01*
X766900Y-574033D01*
X766800Y-575100D01*
X766400Y-576033D01*
X765800Y-576567D01*
X765200Y-576700D01*
G01X771500Y-571367D02*
Y-575100D01*
X771900Y-576033D01*
X772500Y-576567D01*
X773200Y-576700D01*
X773900Y-576567D01*
X774500Y-576033D01*
X774900Y-575100D01*
G01Y-576700D02*
Y-571367D01*
G01X779800Y-578700D02*
X780500Y-579233D01*
X781300Y-579367D01*
X782000Y-579233D01*
X782600Y-578567D01*
X783000Y-577633D01*
Y-571367D01*
G01Y-572433D02*
X782600Y-571900D01*
X782000Y-571500D01*
X781300Y-571367D01*
X780500Y-571633D01*
X780000Y-572167D01*
X779600Y-573100D01*
X779400Y-574033D01*
X779500Y-574833D01*
X779900Y-575767D01*
X780500Y-576433D01*
X781300Y-576700D01*
X781900Y-576567D01*
X782600Y-576033D01*
X783000Y-575500D01*
G01X787500Y-576700D02*
Y-568700D01*
G01Y-572567D02*
X788000Y-571900D01*
X788500Y-571500D01*
X789300Y-571367D01*
X789900Y-571500D01*
X790600Y-572033D01*
X790900Y-572833D01*
Y-576700D01*
G01X795500D02*
Y-571367D01*
G01Y-572700D02*
X795900Y-572033D01*
X796500Y-571500D01*
X797300Y-571367D01*
X798000Y-571500D01*
X798600Y-572033D01*
X798900Y-572967D01*
Y-576700D01*
G01X803700Y-573100D02*
X806900D01*
X806600Y-572167D01*
X806100Y-571633D01*
X805400Y-571367D01*
X804700Y-571500D01*
X804100Y-571900D01*
X803700Y-572833D01*
X803500Y-573634D01*
Y-574433D01*
X803700Y-575233D01*
X804200Y-576033D01*
X804800Y-576567D01*
X805500Y-576700D01*
X806200Y-576433D01*
X806900Y-575634D01*
G01X811700Y-575767D02*
X812200Y-576300D01*
X812900Y-576700D01*
X813500D01*
X814100Y-576433D01*
X814500Y-576033D01*
X814700Y-575500D01*
X814600Y-574700D01*
X814200Y-574300D01*
X812400Y-573500D01*
X812000Y-572567D01*
X812200Y-571900D01*
X812600Y-571500D01*
X813200Y-571367D01*
X813800Y-571500D01*
X814400Y-571900D01*
G01X819700Y-575767D02*
X820200Y-576300D01*
X820900Y-576700D01*
X821500D01*
X822100Y-576433D01*
X822500Y-576033D01*
X822700Y-575500D01*
X822600Y-574700D01*
X822200Y-574300D01*
X820400Y-573500D01*
X820000Y-572567D01*
X820200Y-571900D01*
X820600Y-571500D01*
X821200Y-571367D01*
X821800Y-571500D01*
X822400Y-571900D01*
G01X676200Y-564700D02*
X675400Y-564567D01*
X674700Y-564033D01*
X674100Y-563233D01*
X673700Y-562300D01*
X673500Y-561233D01*
Y-560167D01*
X673700Y-559100D01*
X674100Y-558167D01*
X674700Y-557367D01*
X675400Y-556833D01*
X676200Y-556700D01*
X677000Y-556833D01*
X677700Y-557367D01*
X678300Y-558167D01*
X678700Y-559100D01*
X678900Y-560167D01*
Y-561233D01*
X678700Y-562300D01*
X678300Y-563233D01*
X677700Y-564033D01*
X677000Y-564567D01*
X676200Y-564700D01*
G01X684200Y-556700D02*
Y-564700D01*
G01X682800Y-559367D02*
X685600D01*
G01X690500Y-564700D02*
Y-556700D01*
G01Y-560567D02*
X691000Y-559900D01*
X691500Y-559500D01*
X692300Y-559367D01*
X692900Y-559500D01*
X693600Y-560033D01*
X693900Y-560833D01*
Y-564700D01*
G01X698700Y-561100D02*
X701900D01*
X701600Y-560167D01*
X701100Y-559633D01*
X700400Y-559367D01*
X699700Y-559500D01*
X699100Y-559900D01*
X698700Y-560833D01*
X698500Y-561634D01*
Y-562433D01*
X698700Y-563233D01*
X699200Y-564033D01*
X699800Y-564567D01*
X700500Y-564700D01*
X701200Y-564433D01*
X701900Y-563634D01*
G01X706800Y-564700D02*
Y-559367D01*
G01Y-560433D02*
X707300Y-559900D01*
X707800Y-559500D01*
X708500Y-559367D01*
X709000Y-559500D01*
X709600Y-559900D01*
G01X714700Y-563767D02*
X715200Y-564300D01*
X715900Y-564700D01*
X716500D01*
X717100Y-564433D01*
X717500Y-564033D01*
X717700Y-563500D01*
X717600Y-562700D01*
X717200Y-562300D01*
X715400Y-561500D01*
X715000Y-560567D01*
X715200Y-559900D01*
X715600Y-559500D01*
X716200Y-559367D01*
X716800Y-559500D01*
X717400Y-559900D01*
G01X731700Y-567367D02*
X730700Y-566033D01*
X730200Y-564700D01*
Y-559367D01*
X730700Y-558033D01*
X731700Y-556700D01*
G01X740200Y-564700D02*
Y-556700D01*
G01X748200Y-559367D02*
Y-564700D01*
G01Y-557233D02*
X748000Y-557100D01*
Y-556833D01*
X748200Y-556700D01*
X748400Y-556833D01*
Y-557100D01*
X748200Y-557233D01*
G01X754500Y-564700D02*
Y-556700D01*
G01X757700Y-559367D02*
X754500Y-562433D01*
G01X755800Y-561233D02*
X757900Y-564700D01*
G01X762700Y-561100D02*
X765900D01*
X765600Y-560167D01*
X765100Y-559633D01*
X764400Y-559367D01*
X763700Y-559500D01*
X763100Y-559900D01*
X762700Y-560833D01*
X762500Y-561634D01*
Y-562433D01*
X762700Y-563233D01*
X763200Y-564033D01*
X763800Y-564567D01*
X764500Y-564700D01*
X765200Y-564433D01*
X765900Y-563634D01*
G01X778700Y-561100D02*
X781900D01*
X781600Y-560167D01*
X781100Y-559633D01*
X780400Y-559367D01*
X779700Y-559500D01*
X779100Y-559900D01*
X778700Y-560833D01*
X778500Y-561634D01*
Y-562433D01*
X778700Y-563233D01*
X779200Y-564033D01*
X779800Y-564567D01*
X780500Y-564700D01*
X781200Y-564433D01*
X781900Y-563634D01*
G01X788200Y-564700D02*
Y-556700D01*
G01X796200Y-564700D02*
Y-556700D01*
G01X804200Y-559367D02*
Y-564700D01*
G01Y-557233D02*
X804000Y-557100D01*
Y-556833D01*
X804200Y-556700D01*
X804400Y-556833D01*
Y-557100D01*
X804200Y-557233D01*
G01X810400Y-567367D02*
Y-559367D01*
G01Y-560567D02*
X810900Y-559900D01*
X811400Y-559500D01*
X812200Y-559367D01*
X812900Y-559500D01*
X813600Y-560167D01*
X813900Y-561100D01*
X814000Y-562033D01*
X813900Y-562967D01*
X813600Y-563900D01*
X813000Y-564433D01*
X812200Y-564700D01*
X811500Y-564567D01*
X810800Y-564167D01*
X810400Y-563634D01*
G01X818700Y-563767D02*
X819200Y-564300D01*
X819900Y-564700D01*
X820500D01*
X821100Y-564433D01*
X821500Y-564033D01*
X821700Y-563500D01*
X821600Y-562700D01*
X821200Y-562300D01*
X819400Y-561500D01*
X819000Y-560567D01*
X819200Y-559900D01*
X819600Y-559500D01*
X820200Y-559367D01*
X820800Y-559500D01*
X821400Y-559900D01*
G01X826700Y-561100D02*
X829900D01*
X829600Y-560167D01*
X829100Y-559633D01*
X828400Y-559367D01*
X827700Y-559500D01*
X827100Y-559900D01*
X826700Y-560833D01*
X826500Y-561634D01*
Y-562433D01*
X826700Y-563233D01*
X827200Y-564033D01*
X827800Y-564567D01*
X828500Y-564700D01*
X829200Y-564433D01*
X829900Y-563634D01*
G01X846000Y-564700D02*
Y-559367D01*
G01Y-560300D02*
X845600Y-559767D01*
X845000Y-559500D01*
X844300Y-559367D01*
X843600Y-559633D01*
X843000Y-560167D01*
X842600Y-560967D01*
X842400Y-562033D01*
X842600Y-563100D01*
X843000Y-563900D01*
X843600Y-564433D01*
X844300Y-564700D01*
X845000Y-564567D01*
X845600Y-564167D01*
X846000Y-563634D01*
G01X850500Y-564700D02*
Y-559367D01*
G01Y-560700D02*
X850900Y-560033D01*
X851500Y-559500D01*
X852300Y-559367D01*
X853000Y-559500D01*
X853600Y-560033D01*
X853900Y-560967D01*
Y-564700D01*
G01X862000Y-556700D02*
Y-564700D01*
G01Y-563500D02*
X861600Y-564167D01*
X861000Y-564567D01*
X860300Y-564700D01*
X859500Y-564433D01*
X858900Y-563767D01*
X858500Y-562967D01*
X858400Y-562033D01*
X858500Y-561100D01*
X858900Y-560300D01*
X859500Y-559633D01*
X860300Y-559367D01*
X861000Y-559500D01*
X861500Y-559767D01*
X862000Y-560300D01*
G01X876200Y-564700D02*
X875600Y-564567D01*
X875000Y-564033D01*
X874600Y-563100D01*
X874400Y-562033D01*
X874600Y-560967D01*
X875000Y-560033D01*
X875600Y-559500D01*
X876200Y-559367D01*
X876800Y-559500D01*
X877400Y-560033D01*
X877800Y-560967D01*
X877900Y-562033D01*
X877800Y-563100D01*
X877400Y-564033D01*
X876800Y-564567D01*
X876200Y-564700D01*
G01X884200Y-556700D02*
Y-564700D01*
G01X882800Y-559367D02*
X885600D01*
G01X890500Y-564700D02*
Y-556700D01*
G01Y-560567D02*
X891000Y-559900D01*
X891500Y-559500D01*
X892300Y-559367D01*
X892900Y-559500D01*
X893600Y-560033D01*
X893900Y-560833D01*
Y-564700D01*
G01X898700Y-561100D02*
X901900D01*
X901600Y-560167D01*
X901100Y-559633D01*
X900400Y-559367D01*
X899700Y-559500D01*
X899100Y-559900D01*
X898700Y-560833D01*
X898500Y-561634D01*
Y-562433D01*
X898700Y-563233D01*
X899200Y-564033D01*
X899800Y-564567D01*
X900500Y-564700D01*
X901200Y-564433D01*
X901900Y-563634D01*
G01X906800Y-564700D02*
Y-559367D01*
G01Y-560433D02*
X907300Y-559900D01*
X907800Y-559500D01*
X908500Y-559367D01*
X909000Y-559500D01*
X909600Y-559900D01*
G01X914700Y-563767D02*
X915200Y-564300D01*
X915900Y-564700D01*
X916500D01*
X917100Y-564433D01*
X917500Y-564033D01*
X917700Y-563500D01*
X917600Y-562700D01*
X917200Y-562300D01*
X915400Y-561500D01*
X915000Y-560567D01*
X915200Y-559900D01*
X915600Y-559500D01*
X916200Y-559367D01*
X916800Y-559500D01*
X917400Y-559900D01*
G01X924700Y-567367D02*
X925700Y-566033D01*
X926200Y-564700D01*
Y-559367D01*
X925700Y-558033D01*
X924700Y-556700D01*
G01X674200Y-553200D02*
Y-545200D01*
X676600D01*
X677400Y-545600D01*
X678000Y-546533D01*
X678200Y-547600D01*
X678000Y-548667D01*
X677500Y-549467D01*
X676600Y-549867D01*
X674200D01*
G01X684200Y-545200D02*
Y-553200D01*
G01X681900Y-545200D02*
X686500D01*
G01X690100Y-553200D02*
Y-545200D01*
G01X694300D02*
Y-553200D01*
G01Y-549200D02*
X690100D01*
G01X698400Y-553467D02*
X702000Y-545200D01*
G01X705900Y-553200D02*
Y-545200D01*
X710500Y-553200D01*
Y-545200D01*
G01X714200Y-553200D02*
Y-545200D01*
X716600D01*
X717400Y-545600D01*
X718000Y-546533D01*
X718200Y-547600D01*
X718000Y-548667D01*
X717500Y-549467D01*
X716600Y-549867D01*
X714200D01*
G01X724200Y-545200D02*
Y-553200D01*
G01X721900Y-545200D02*
X726500D01*
G01X730100Y-553200D02*
Y-545200D01*
G01X734300D02*
Y-553200D01*
G01Y-549200D02*
X730100D01*
G01X746200Y-553200D02*
X750200Y-550533D01*
X746200Y-547867D01*
G01X754900Y-551733D02*
X757500D01*
G01Y-549333D02*
X754900D01*
G01X762000Y-552000D02*
X762600Y-552667D01*
X763300Y-553067D01*
X764200Y-553200D01*
X765100Y-552933D01*
X765800Y-552400D01*
X766300Y-551467D01*
X766400Y-550400D01*
X766200Y-549333D01*
X765700Y-548667D01*
X765000Y-548133D01*
X764300Y-548000D01*
X763600Y-548133D01*
X762700Y-548667D01*
X763000Y-545200D01*
X765700D01*
G01X777200Y-553200D02*
Y-547867D01*
G01Y-549333D02*
X777500Y-548667D01*
X778000Y-548133D01*
X778700Y-547867D01*
X779400Y-548133D01*
X779900Y-548667D01*
X780200Y-549333D01*
Y-553200D01*
G01Y-549333D02*
X780500Y-548667D01*
X781000Y-548133D01*
X781700Y-547867D01*
X782400Y-548133D01*
X782900Y-548667D01*
X783200Y-549467D01*
Y-553200D01*
G01X785200D02*
Y-547867D01*
G01Y-549333D02*
X785500Y-548667D01*
X786000Y-548133D01*
X786700Y-547867D01*
X787400Y-548133D01*
X787900Y-548667D01*
X788200Y-549333D01*
Y-553200D01*
G01Y-549333D02*
X788500Y-548667D01*
X789000Y-548133D01*
X789700Y-547867D01*
X790400Y-548133D01*
X790900Y-548667D01*
X791200Y-549467D01*
Y-553200D01*
G01X674400Y-528200D02*
Y-520200D01*
X679000Y-528200D01*
Y-520200D01*
G01X682700Y-528200D02*
Y-520200D01*
X685100D01*
X685900Y-520600D01*
X686500Y-521533D01*
X686700Y-522600D01*
X686500Y-523667D01*
X686000Y-524467D01*
X685100Y-524867D01*
X682700D01*
G01X692700Y-520200D02*
Y-528200D01*
G01X690400Y-520200D02*
X695000D01*
G01X698600Y-528200D02*
Y-520200D01*
G01X702800D02*
Y-528200D01*
G01Y-524200D02*
X698600D01*
G01X714600Y-527134D02*
X715400Y-527800D01*
X716300Y-528200D01*
X717100D01*
X717900Y-527800D01*
X718500Y-527134D01*
X718800Y-526200D01*
X718600Y-525267D01*
X718100Y-524467D01*
X717200Y-523933D01*
X716000Y-523667D01*
X715300Y-523133D01*
X715000Y-522200D01*
X715200Y-521267D01*
X715700Y-520600D01*
X716400Y-520200D01*
X717100D01*
X717800Y-520467D01*
X718400Y-521133D01*
G01X724700Y-522867D02*
Y-528200D01*
G01Y-520733D02*
X724500Y-520600D01*
Y-520333D01*
X724700Y-520200D01*
X724900Y-520333D01*
Y-520600D01*
X724700Y-520733D01*
G01X731200Y-522867D02*
X734200D01*
X731200Y-528200D01*
X734200D01*
G01X739200Y-524600D02*
X742400D01*
X742100Y-523667D01*
X741600Y-523133D01*
X740900Y-522867D01*
X740200Y-523000D01*
X739600Y-523400D01*
X739200Y-524333D01*
X739000Y-525134D01*
Y-525933D01*
X739200Y-526733D01*
X739700Y-527533D01*
X740300Y-528067D01*
X741000Y-528200D01*
X741700Y-527933D01*
X742400Y-527134D01*
G01X754500Y-526600D02*
X755100Y-527533D01*
X755900Y-528067D01*
X756800Y-528200D01*
X757600Y-528067D01*
X758400Y-527400D01*
X758900Y-526600D01*
X759000Y-525800D01*
X758800Y-524867D01*
X758100Y-524200D01*
X757400Y-523933D01*
X756500D01*
G01X757400D02*
X758000Y-523533D01*
X758500Y-522867D01*
X758700Y-522067D01*
X758500Y-521267D01*
X758000Y-520600D01*
X757100Y-520200D01*
X756200Y-520333D01*
X755300Y-520867D01*
G01X764700Y-528467D02*
X764500Y-528333D01*
Y-528067D01*
X764700Y-527933D01*
X764900Y-528067D01*
Y-528333D01*
X764700Y-528467D01*
G01X770500Y-527000D02*
X771100Y-527667D01*
X771800Y-528067D01*
X772700Y-528200D01*
X773600Y-527933D01*
X774300Y-527400D01*
X774800Y-526467D01*
X774900Y-525400D01*
X774700Y-524333D01*
X774200Y-523667D01*
X773500Y-523133D01*
X772800Y-523000D01*
X772100Y-523133D01*
X771200Y-523667D01*
X771500Y-520200D01*
X774200D01*
G01X778500Y-527000D02*
X779100Y-527667D01*
X779800Y-528067D01*
X780700Y-528200D01*
X781600Y-527933D01*
X782300Y-527400D01*
X782800Y-526467D01*
X782900Y-525400D01*
X782700Y-524333D01*
X782200Y-523667D01*
X781500Y-523133D01*
X780800Y-523000D01*
X780100Y-523133D01*
X779200Y-523667D01*
X779500Y-520200D01*
X782200D01*
G01X785700Y-528200D02*
Y-522867D01*
G01Y-524333D02*
X786000Y-523667D01*
X786500Y-523133D01*
X787200Y-522867D01*
X787900Y-523133D01*
X788400Y-523667D01*
X788700Y-524333D01*
Y-528200D01*
G01Y-524333D02*
X789000Y-523667D01*
X789500Y-523133D01*
X790200Y-522867D01*
X790900Y-523133D01*
X791400Y-523667D01*
X791700Y-524467D01*
Y-528200D01*
G01X793700D02*
Y-522867D01*
G01Y-524333D02*
X794000Y-523667D01*
X794500Y-523133D01*
X795200Y-522867D01*
X795900Y-523133D01*
X796400Y-523667D01*
X796700Y-524333D01*
Y-528200D01*
G01Y-524333D02*
X797000Y-523667D01*
X797500Y-523133D01*
X798200Y-522867D01*
X798900Y-523133D01*
X799400Y-523667D01*
X799700Y-524467D01*
Y-528200D01*
G01X812200Y-530867D02*
X811200Y-529533D01*
X810700Y-528200D01*
Y-522867D01*
X811200Y-521533D01*
X812200Y-520200D01*
G01X820700Y-528200D02*
X820100Y-528067D01*
X819500Y-527533D01*
X819100Y-526600D01*
X818900Y-525533D01*
X819100Y-524467D01*
X819500Y-523533D01*
X820100Y-523000D01*
X820700Y-522867D01*
X821300Y-523000D01*
X821900Y-523533D01*
X822300Y-524467D01*
X822400Y-525533D01*
X822300Y-526600D01*
X821900Y-527533D01*
X821300Y-528067D01*
X820700Y-528200D01*
G01X827000D02*
Y-522867D01*
G01Y-524200D02*
X827400Y-523533D01*
X828000Y-523000D01*
X828800Y-522867D01*
X829500Y-523000D01*
X830100Y-523533D01*
X830400Y-524467D01*
Y-528200D01*
G01X842900D02*
Y-520200D01*
G01Y-524200D02*
X843400Y-523400D01*
X844000Y-523000D01*
X844600Y-522867D01*
X845500Y-523133D01*
X846100Y-523667D01*
X846500Y-524600D01*
Y-525667D01*
X846300Y-526733D01*
X845900Y-527533D01*
X845200Y-528067D01*
X844600Y-528200D01*
X844000Y-528067D01*
X843400Y-527667D01*
X842900Y-527000D01*
G01X851300Y-528200D02*
Y-522867D01*
G01Y-523933D02*
X851800Y-523400D01*
X852300Y-523000D01*
X853000Y-522867D01*
X853500Y-523000D01*
X854100Y-523400D01*
G01X859200Y-524600D02*
X862400D01*
X862100Y-523667D01*
X861600Y-523133D01*
X860900Y-522867D01*
X860200Y-523000D01*
X859600Y-523400D01*
X859200Y-524333D01*
X859000Y-525134D01*
Y-525933D01*
X859200Y-526733D01*
X859700Y-527533D01*
X860300Y-528067D01*
X861000Y-528200D01*
X861700Y-527933D01*
X862400Y-527134D01*
G01X870500Y-528200D02*
Y-522867D01*
G01Y-523800D02*
X870100Y-523267D01*
X869500Y-523000D01*
X868800Y-522867D01*
X868100Y-523133D01*
X867500Y-523667D01*
X867100Y-524467D01*
X866900Y-525533D01*
X867100Y-526600D01*
X867500Y-527400D01*
X868100Y-527933D01*
X868800Y-528200D01*
X869500Y-528067D01*
X870100Y-527667D01*
X870500Y-527134D01*
G01X875000Y-528200D02*
Y-520200D01*
G01X878200Y-522867D02*
X875000Y-525933D01*
G01X876300Y-524733D02*
X878400Y-528200D01*
G01X886500D02*
Y-522867D01*
G01Y-523800D02*
X886100Y-523267D01*
X885500Y-523000D01*
X884800Y-522867D01*
X884100Y-523133D01*
X883500Y-523667D01*
X883100Y-524467D01*
X882900Y-525533D01*
X883100Y-526600D01*
X883500Y-527400D01*
X884100Y-527933D01*
X884800Y-528200D01*
X885500Y-528067D01*
X886100Y-527667D01*
X886500Y-527134D01*
G01X890200Y-522867D02*
X891400Y-528200D01*
X892700Y-522867D01*
X894000Y-528200D01*
X895200Y-522867D01*
G01X902500Y-528200D02*
Y-522867D01*
G01Y-523800D02*
X902100Y-523267D01*
X901500Y-523000D01*
X900800Y-522867D01*
X900100Y-523133D01*
X899500Y-523667D01*
X899100Y-524467D01*
X898900Y-525533D01*
X899100Y-526600D01*
X899500Y-527400D01*
X900100Y-527933D01*
X900800Y-528200D01*
X901500Y-528067D01*
X902100Y-527667D01*
X902500Y-527134D01*
G01X906600Y-530600D02*
X907200Y-530867D01*
X908000Y-530600D01*
X908500Y-530067D01*
X908900Y-529400D01*
X909500Y-527267D01*
X910800Y-522867D01*
G01X907600D02*
X909500Y-527267D01*
G01X917200Y-530867D02*
X918200Y-529533D01*
X918700Y-528200D01*
Y-522867D01*
X918200Y-521533D01*
X917200Y-520200D01*
G01X674400Y-540200D02*
Y-532200D01*
X679000Y-540200D01*
Y-532200D01*
G01X682700Y-540200D02*
Y-532200D01*
X685100D01*
X685900Y-532600D01*
X686500Y-533533D01*
X686700Y-534600D01*
X686500Y-535667D01*
X686000Y-536467D01*
X685100Y-536867D01*
X682700D01*
G01X692700Y-532200D02*
Y-540200D01*
G01X690400Y-532200D02*
X695000D01*
G01X698600Y-540200D02*
Y-532200D01*
G01X702800D02*
Y-540200D01*
G01Y-536200D02*
X698600D01*
G01X714600Y-539134D02*
X715400Y-539800D01*
X716300Y-540200D01*
X717100D01*
X717900Y-539800D01*
X718500Y-539134D01*
X718800Y-538200D01*
X718600Y-537267D01*
X718100Y-536467D01*
X717200Y-535933D01*
X716000Y-535667D01*
X715300Y-535133D01*
X715000Y-534200D01*
X715200Y-533267D01*
X715700Y-532600D01*
X716400Y-532200D01*
X717100D01*
X717800Y-532467D01*
X718400Y-533133D01*
G01X724700Y-534867D02*
Y-540200D01*
G01Y-532733D02*
X724500Y-532600D01*
Y-532333D01*
X724700Y-532200D01*
X724900Y-532333D01*
Y-532600D01*
X724700Y-532733D01*
G01X731200Y-534867D02*
X734200D01*
X731200Y-540200D01*
X734200D01*
G01X739200Y-536600D02*
X742400D01*
X742100Y-535667D01*
X741600Y-535133D01*
X740900Y-534867D01*
X740200Y-535000D01*
X739600Y-535400D01*
X739200Y-536333D01*
X739000Y-537134D01*
Y-537933D01*
X739200Y-538733D01*
X739700Y-539533D01*
X740300Y-540067D01*
X741000Y-540200D01*
X741700Y-539933D01*
X742400Y-539134D01*
G01X754800Y-533533D02*
X755400Y-532733D01*
X756100Y-532333D01*
X756900Y-532200D01*
X757900Y-532467D01*
X758600Y-533133D01*
X758800Y-533933D01*
X758700Y-534734D01*
X758300Y-535400D01*
X756300Y-536733D01*
X755400Y-537667D01*
X754800Y-539000D01*
X754600Y-540200D01*
X758800D01*
G01X764700Y-540467D02*
X764500Y-540333D01*
Y-540067D01*
X764700Y-539933D01*
X764900Y-540067D01*
Y-540333D01*
X764700Y-540467D01*
G01X772700Y-540200D02*
Y-532200D01*
X771500Y-533800D01*
G01Y-540200D02*
X773900D01*
G01X780700D02*
X781400Y-540067D01*
X782200Y-539667D01*
X782700Y-539000D01*
X782900Y-538067D01*
X782700Y-537134D01*
X782100Y-536333D01*
X781200Y-535933D01*
X780200D01*
X779600Y-535667D01*
X779100Y-535000D01*
X778900Y-534067D01*
X779200Y-533133D01*
X779900Y-532467D01*
X780700Y-532200D01*
X781500Y-532467D01*
X782200Y-533133D01*
X782500Y-534067D01*
X782300Y-535000D01*
X781800Y-535667D01*
X781200Y-535933D01*
X780200D01*
X779300Y-536333D01*
X778700Y-537134D01*
X778500Y-538067D01*
X778700Y-539000D01*
X779200Y-539667D01*
X780000Y-540067D01*
X780700Y-540200D01*
G01X785700D02*
Y-534867D01*
G01Y-536333D02*
X786000Y-535667D01*
X786500Y-535133D01*
X787200Y-534867D01*
X787900Y-535133D01*
X788400Y-535667D01*
X788700Y-536333D01*
Y-540200D01*
G01Y-536333D02*
X789000Y-535667D01*
X789500Y-535133D01*
X790200Y-534867D01*
X790900Y-535133D01*
X791400Y-535667D01*
X791700Y-536467D01*
Y-540200D01*
G01X793700D02*
Y-534867D01*
G01Y-536333D02*
X794000Y-535667D01*
X794500Y-535133D01*
X795200Y-534867D01*
X795900Y-535133D01*
X796400Y-535667D01*
X796700Y-536333D01*
Y-540200D01*
G01Y-536333D02*
X797000Y-535667D01*
X797500Y-535133D01*
X798200Y-534867D01*
X798900Y-535133D01*
X799400Y-535667D01*
X799700Y-536467D01*
Y-540200D01*
G01X812200Y-542867D02*
X811200Y-541533D01*
X810700Y-540200D01*
Y-534867D01*
X811200Y-533533D01*
X812200Y-532200D01*
G01X820700Y-540200D02*
X820100Y-540067D01*
X819500Y-539533D01*
X819100Y-538600D01*
X818900Y-537533D01*
X819100Y-536467D01*
X819500Y-535533D01*
X820100Y-535000D01*
X820700Y-534867D01*
X821300Y-535000D01*
X821900Y-535533D01*
X822300Y-536467D01*
X822400Y-537533D01*
X822300Y-538600D01*
X821900Y-539533D01*
X821300Y-540067D01*
X820700Y-540200D01*
G01X827000D02*
Y-534867D01*
G01Y-536200D02*
X827400Y-535533D01*
X828000Y-535000D01*
X828800Y-534867D01*
X829500Y-535000D01*
X830100Y-535533D01*
X830400Y-536467D01*
Y-540200D01*
G01X842900D02*
Y-532200D01*
G01Y-536200D02*
X843400Y-535400D01*
X844000Y-535000D01*
X844600Y-534867D01*
X845500Y-535133D01*
X846100Y-535667D01*
X846500Y-536600D01*
Y-537667D01*
X846300Y-538733D01*
X845900Y-539533D01*
X845200Y-540067D01*
X844600Y-540200D01*
X844000Y-540067D01*
X843400Y-539667D01*
X842900Y-539000D01*
G01X851300Y-540200D02*
Y-534867D01*
G01Y-535933D02*
X851800Y-535400D01*
X852300Y-535000D01*
X853000Y-534867D01*
X853500Y-535000D01*
X854100Y-535400D01*
G01X859200Y-536600D02*
X862400D01*
X862100Y-535667D01*
X861600Y-535133D01*
X860900Y-534867D01*
X860200Y-535000D01*
X859600Y-535400D01*
X859200Y-536333D01*
X859000Y-537134D01*
Y-537933D01*
X859200Y-538733D01*
X859700Y-539533D01*
X860300Y-540067D01*
X861000Y-540200D01*
X861700Y-539933D01*
X862400Y-539134D01*
G01X870500Y-540200D02*
Y-534867D01*
G01Y-535800D02*
X870100Y-535267D01*
X869500Y-535000D01*
X868800Y-534867D01*
X868100Y-535133D01*
X867500Y-535667D01*
X867100Y-536467D01*
X866900Y-537533D01*
X867100Y-538600D01*
X867500Y-539400D01*
X868100Y-539933D01*
X868800Y-540200D01*
X869500Y-540067D01*
X870100Y-539667D01*
X870500Y-539134D01*
G01X875000Y-540200D02*
Y-532200D01*
G01X878200Y-534867D02*
X875000Y-537933D01*
G01X876300Y-536733D02*
X878400Y-540200D01*
G01X886500D02*
Y-534867D01*
G01Y-535800D02*
X886100Y-535267D01*
X885500Y-535000D01*
X884800Y-534867D01*
X884100Y-535133D01*
X883500Y-535667D01*
X883100Y-536467D01*
X882900Y-537533D01*
X883100Y-538600D01*
X883500Y-539400D01*
X884100Y-539933D01*
X884800Y-540200D01*
X885500Y-540067D01*
X886100Y-539667D01*
X886500Y-539134D01*
G01X890200Y-534867D02*
X891400Y-540200D01*
X892700Y-534867D01*
X894000Y-540200D01*
X895200Y-534867D01*
G01X902500Y-540200D02*
Y-534867D01*
G01Y-535800D02*
X902100Y-535267D01*
X901500Y-535000D01*
X900800Y-534867D01*
X900100Y-535133D01*
X899500Y-535667D01*
X899100Y-536467D01*
X898900Y-537533D01*
X899100Y-538600D01*
X899500Y-539400D01*
X900100Y-539933D01*
X900800Y-540200D01*
X901500Y-540067D01*
X902100Y-539667D01*
X902500Y-539134D01*
G01X906600Y-542600D02*
X907200Y-542867D01*
X908000Y-542600D01*
X908500Y-542067D01*
X908900Y-541400D01*
X909500Y-539267D01*
X910800Y-534867D01*
G01X907600D02*
X909500Y-539267D01*
G01X917200Y-542867D02*
X918200Y-541533D01*
X918700Y-540200D01*
Y-534867D01*
X918200Y-533533D01*
X917200Y-532200D01*
G01X674400Y-514700D02*
Y-506700D01*
X679000Y-514700D01*
Y-506700D01*
G01X682700Y-514700D02*
Y-506700D01*
X685100D01*
X685900Y-507100D01*
X686500Y-508033D01*
X686700Y-509100D01*
X686500Y-510167D01*
X686000Y-510967D01*
X685100Y-511367D01*
X682700D01*
G01X692700Y-506700D02*
Y-514700D01*
G01X690400Y-506700D02*
X695000D01*
G01X698600Y-514700D02*
Y-506700D01*
G01X702800D02*
Y-514700D01*
G01Y-510700D02*
X698600D01*
G01X714600Y-513634D02*
X715400Y-514300D01*
X716300Y-514700D01*
X717100D01*
X717900Y-514300D01*
X718500Y-513634D01*
X718800Y-512700D01*
X718600Y-511767D01*
X718100Y-510967D01*
X717200Y-510433D01*
X716000Y-510167D01*
X715300Y-509633D01*
X715000Y-508700D01*
X715200Y-507767D01*
X715700Y-507100D01*
X716400Y-506700D01*
X717100D01*
X717800Y-506967D01*
X718400Y-507633D01*
G01X724700Y-509367D02*
Y-514700D01*
G01Y-507233D02*
X724500Y-507100D01*
Y-506833D01*
X724700Y-506700D01*
X724900Y-506833D01*
Y-507100D01*
X724700Y-507233D01*
G01X731200Y-509367D02*
X734200D01*
X731200Y-514700D01*
X734200D01*
G01X739200Y-511100D02*
X742400D01*
X742100Y-510167D01*
X741600Y-509633D01*
X740900Y-509367D01*
X740200Y-509500D01*
X739600Y-509900D01*
X739200Y-510833D01*
X739000Y-511634D01*
Y-512433D01*
X739200Y-513233D01*
X739700Y-514033D01*
X740300Y-514567D01*
X741000Y-514700D01*
X741700Y-514433D01*
X742400Y-513634D01*
G01X750700Y-514700D02*
X746700Y-512033D01*
X750700Y-509367D01*
G01X762500Y-513500D02*
X763100Y-514167D01*
X763800Y-514567D01*
X764700Y-514700D01*
X765600Y-514433D01*
X766300Y-513900D01*
X766800Y-512967D01*
X766900Y-511900D01*
X766700Y-510833D01*
X766200Y-510167D01*
X765500Y-509633D01*
X764800Y-509500D01*
X764100Y-509633D01*
X763200Y-510167D01*
X763500Y-506700D01*
X766200D01*
G01X769700Y-514700D02*
Y-509367D01*
G01Y-510833D02*
X770000Y-510167D01*
X770500Y-509633D01*
X771200Y-509367D01*
X771900Y-509633D01*
X772400Y-510167D01*
X772700Y-510833D01*
Y-514700D01*
G01Y-510833D02*
X773000Y-510167D01*
X773500Y-509633D01*
X774200Y-509367D01*
X774900Y-509633D01*
X775400Y-510167D01*
X775700Y-510967D01*
Y-514700D01*
G01X777700D02*
Y-509367D01*
G01Y-510833D02*
X778000Y-510167D01*
X778500Y-509633D01*
X779200Y-509367D01*
X779900Y-509633D01*
X780400Y-510167D01*
X780700Y-510833D01*
Y-514700D01*
G01Y-510833D02*
X781000Y-510167D01*
X781500Y-509633D01*
X782200Y-509367D01*
X782900Y-509633D01*
X783400Y-510167D01*
X783700Y-510967D01*
Y-514700D01*
G01X796200Y-517367D02*
X795200Y-516033D01*
X794700Y-514700D01*
Y-509367D01*
X795200Y-508033D01*
X796200Y-506700D01*
G01X803000Y-514700D02*
Y-509367D01*
G01Y-510700D02*
X803400Y-510033D01*
X804000Y-509500D01*
X804800Y-509367D01*
X805500Y-509500D01*
X806100Y-510033D01*
X806400Y-510967D01*
Y-514700D01*
G01X812700D02*
X812100Y-514567D01*
X811500Y-514033D01*
X811100Y-513100D01*
X810900Y-512033D01*
X811100Y-510967D01*
X811500Y-510033D01*
X812100Y-509500D01*
X812700Y-509367D01*
X813300Y-509500D01*
X813900Y-510033D01*
X814300Y-510967D01*
X814400Y-512033D01*
X814300Y-513100D01*
X813900Y-514033D01*
X813300Y-514567D01*
X812700Y-514700D01*
G01X820700Y-506700D02*
Y-514700D01*
G01X819300Y-509367D02*
X822100D01*
G01X836700Y-514700D02*
X836100Y-514567D01*
X835500Y-514033D01*
X835100Y-513100D01*
X834900Y-512033D01*
X835100Y-510967D01*
X835500Y-510033D01*
X836100Y-509500D01*
X836700Y-509367D01*
X837300Y-509500D01*
X837900Y-510033D01*
X838300Y-510967D01*
X838400Y-512033D01*
X838300Y-513100D01*
X837900Y-514033D01*
X837300Y-514567D01*
X836700Y-514700D01*
G01X843000D02*
Y-509367D01*
G01Y-510700D02*
X843400Y-510033D01*
X844000Y-509500D01*
X844800Y-509367D01*
X845500Y-509500D01*
X846100Y-510033D01*
X846400Y-510967D01*
Y-514700D01*
G01X858900D02*
Y-506700D01*
G01Y-510700D02*
X859400Y-509900D01*
X860000Y-509500D01*
X860600Y-509367D01*
X861500Y-509633D01*
X862100Y-510167D01*
X862500Y-511100D01*
Y-512167D01*
X862300Y-513233D01*
X861900Y-514033D01*
X861200Y-514567D01*
X860600Y-514700D01*
X860000Y-514567D01*
X859400Y-514167D01*
X858900Y-513500D01*
G01X867300Y-514700D02*
Y-509367D01*
G01Y-510433D02*
X867800Y-509900D01*
X868300Y-509500D01*
X869000Y-509367D01*
X869500Y-509500D01*
X870100Y-509900D01*
G01X875200Y-511100D02*
X878400D01*
X878100Y-510167D01*
X877600Y-509633D01*
X876900Y-509367D01*
X876200Y-509500D01*
X875600Y-509900D01*
X875200Y-510833D01*
X875000Y-511634D01*
Y-512433D01*
X875200Y-513233D01*
X875700Y-514033D01*
X876300Y-514567D01*
X877000Y-514700D01*
X877700Y-514433D01*
X878400Y-513634D01*
G01X886500Y-514700D02*
Y-509367D01*
G01Y-510300D02*
X886100Y-509767D01*
X885500Y-509500D01*
X884800Y-509367D01*
X884100Y-509633D01*
X883500Y-510167D01*
X883100Y-510967D01*
X882900Y-512033D01*
X883100Y-513100D01*
X883500Y-513900D01*
X884100Y-514433D01*
X884800Y-514700D01*
X885500Y-514567D01*
X886100Y-514167D01*
X886500Y-513634D01*
G01X891000Y-514700D02*
Y-506700D01*
G01X894200Y-509367D02*
X891000Y-512433D01*
G01X892300Y-511233D02*
X894400Y-514700D01*
G01X902500D02*
Y-509367D01*
G01Y-510300D02*
X902100Y-509767D01*
X901500Y-509500D01*
X900800Y-509367D01*
X900100Y-509633D01*
X899500Y-510167D01*
X899100Y-510967D01*
X898900Y-512033D01*
X899100Y-513100D01*
X899500Y-513900D01*
X900100Y-514433D01*
X900800Y-514700D01*
X901500Y-514567D01*
X902100Y-514167D01*
X902500Y-513634D01*
G01X906200Y-509367D02*
X907400Y-514700D01*
X908700Y-509367D01*
X910000Y-514700D01*
X911200Y-509367D01*
G01X918500Y-514700D02*
Y-509367D01*
G01Y-510300D02*
X918100Y-509767D01*
X917500Y-509500D01*
X916800Y-509367D01*
X916100Y-509633D01*
X915500Y-510167D01*
X915100Y-510967D01*
X914900Y-512033D01*
X915100Y-513100D01*
X915500Y-513900D01*
X916100Y-514433D01*
X916800Y-514700D01*
X917500Y-514567D01*
X918100Y-514167D01*
X918500Y-513634D01*
G01X922600Y-517100D02*
X923200Y-517367D01*
X924000Y-517100D01*
X924500Y-516567D01*
X924900Y-515900D01*
X925500Y-513767D01*
X926800Y-509367D01*
G01X923600D02*
X925500Y-513767D01*
G01X933200Y-517367D02*
X934200Y-516033D01*
X934700Y-514700D01*
Y-509367D01*
X934200Y-508033D01*
X933200Y-506700D01*
G01X675200Y-503367D02*
X674200Y-502033D01*
X673700Y-500700D01*
Y-495367D01*
X674200Y-494033D01*
X675200Y-492700D01*
G01X681600Y-499634D02*
X682400Y-500300D01*
X683300Y-500700D01*
X684100D01*
X684900Y-500300D01*
X685500Y-499634D01*
X685800Y-498700D01*
X685600Y-497767D01*
X685100Y-496967D01*
X684200Y-496433D01*
X683000Y-496167D01*
X682300Y-495633D01*
X682000Y-494700D01*
X682200Y-493767D01*
X682700Y-493100D01*
X683400Y-492700D01*
X684100D01*
X684800Y-492967D01*
X685400Y-493633D01*
G01X690000Y-495367D02*
Y-499100D01*
X690400Y-500033D01*
X691000Y-500567D01*
X691700Y-500700D01*
X692400Y-500567D01*
X693000Y-500033D01*
X693400Y-499100D01*
G01Y-500700D02*
Y-495367D01*
G01X698300Y-500700D02*
Y-495367D01*
G01Y-496433D02*
X698800Y-495900D01*
X699300Y-495500D01*
X700000Y-495367D01*
X700500Y-495500D01*
X701100Y-495900D01*
G01X707100Y-500700D02*
Y-493900D01*
X707300Y-493233D01*
X707700Y-492833D01*
X708300Y-492700D01*
X708900Y-492967D01*
X709200Y-493633D01*
G01X708000Y-495900D02*
X706000D01*
G01X717500Y-500700D02*
Y-495367D01*
G01Y-496300D02*
X717100Y-495767D01*
X716500Y-495500D01*
X715800Y-495367D01*
X715100Y-495633D01*
X714500Y-496167D01*
X714100Y-496967D01*
X713900Y-498033D01*
X714100Y-499100D01*
X714500Y-499900D01*
X715100Y-500433D01*
X715800Y-500700D01*
X716500Y-500567D01*
X717100Y-500167D01*
X717500Y-499634D01*
G01X725300Y-496033D02*
X724600Y-495500D01*
X724000Y-495367D01*
X723200Y-495633D01*
X722600Y-496167D01*
X722200Y-497100D01*
X722100Y-498033D01*
X722200Y-498967D01*
X722600Y-499767D01*
X723200Y-500433D01*
X724000Y-500700D01*
X724700Y-500433D01*
X725300Y-499900D01*
G01X730200Y-497100D02*
X733400D01*
X733100Y-496167D01*
X732600Y-495633D01*
X731900Y-495367D01*
X731200Y-495500D01*
X730600Y-495900D01*
X730200Y-496833D01*
X730000Y-497634D01*
Y-498433D01*
X730200Y-499233D01*
X730700Y-500033D01*
X731300Y-500567D01*
X732000Y-500700D01*
X732700Y-500433D01*
X733400Y-499634D01*
G01X747700Y-492700D02*
Y-500700D01*
G01X746300Y-495367D02*
X749100D01*
G01X754300Y-500700D02*
Y-495367D01*
G01Y-496433D02*
X754800Y-495900D01*
X755300Y-495500D01*
X756000Y-495367D01*
X756500Y-495500D01*
X757100Y-495900D01*
G01X762200Y-497100D02*
X765400D01*
X765100Y-496167D01*
X764600Y-495633D01*
X763900Y-495367D01*
X763200Y-495500D01*
X762600Y-495900D01*
X762200Y-496833D01*
X762000Y-497634D01*
Y-498433D01*
X762200Y-499233D01*
X762700Y-500033D01*
X763300Y-500567D01*
X764000Y-500700D01*
X764700Y-500433D01*
X765400Y-499634D01*
G01X773500Y-500700D02*
Y-495367D01*
G01Y-496300D02*
X773100Y-495767D01*
X772500Y-495500D01*
X771800Y-495367D01*
X771100Y-495633D01*
X770500Y-496167D01*
X770100Y-496967D01*
X769900Y-498033D01*
X770100Y-499100D01*
X770500Y-499900D01*
X771100Y-500433D01*
X771800Y-500700D01*
X772500Y-500567D01*
X773100Y-500167D01*
X773500Y-499634D01*
G01X779700Y-492700D02*
Y-500700D01*
G01X778300Y-495367D02*
X781100D01*
G01X784700Y-500700D02*
Y-495367D01*
G01Y-496833D02*
X785000Y-496167D01*
X785500Y-495633D01*
X786200Y-495367D01*
X786900Y-495633D01*
X787400Y-496167D01*
X787700Y-496833D01*
Y-500700D01*
G01Y-496833D02*
X788000Y-496167D01*
X788500Y-495633D01*
X789200Y-495367D01*
X789900Y-495633D01*
X790400Y-496167D01*
X790700Y-496967D01*
Y-500700D01*
G01X794200Y-497100D02*
X797400D01*
X797100Y-496167D01*
X796600Y-495633D01*
X795900Y-495367D01*
X795200Y-495500D01*
X794600Y-495900D01*
X794200Y-496833D01*
X794000Y-497634D01*
Y-498433D01*
X794200Y-499233D01*
X794700Y-500033D01*
X795300Y-500567D01*
X796000Y-500700D01*
X796700Y-500433D01*
X797400Y-499634D01*
G01X802000Y-500700D02*
Y-495367D01*
G01Y-496700D02*
X802400Y-496033D01*
X803000Y-495500D01*
X803800Y-495367D01*
X804500Y-495500D01*
X805100Y-496033D01*
X805400Y-496967D01*
Y-500700D01*
G01X811700Y-492700D02*
Y-500700D01*
G01X810300Y-495367D02*
X813100D01*
G01X827700D02*
Y-500700D01*
G01Y-493233D02*
X827500Y-493100D01*
Y-492833D01*
X827700Y-492700D01*
X827900Y-492833D01*
Y-493100D01*
X827700Y-493233D01*
G01X834200Y-499767D02*
X834700Y-500300D01*
X835400Y-500700D01*
X836000D01*
X836600Y-500433D01*
X837000Y-500033D01*
X837200Y-499500D01*
X837100Y-498700D01*
X836700Y-498300D01*
X834900Y-497500D01*
X834500Y-496567D01*
X834700Y-495900D01*
X835100Y-495500D01*
X835700Y-495367D01*
X836300Y-495500D01*
X836900Y-495900D01*
G01X849600Y-500700D02*
Y-492700D01*
G01X853800D02*
Y-500700D01*
G01Y-496700D02*
X849600D01*
G01X857200Y-500700D02*
X859700Y-492700D01*
X862200Y-500700D01*
G01X861300Y-497900D02*
X858100D01*
G01X865600Y-499634D02*
X866400Y-500300D01*
X867300Y-500700D01*
X868100D01*
X868900Y-500300D01*
X869500Y-499634D01*
X869800Y-498700D01*
X869600Y-497767D01*
X869100Y-496967D01*
X868200Y-496433D01*
X867000Y-496167D01*
X866300Y-495633D01*
X866000Y-494700D01*
X866200Y-493767D01*
X866700Y-493100D01*
X867400Y-492700D01*
X868100D01*
X868800Y-492967D01*
X869400Y-493633D01*
G01X873700Y-492700D02*
Y-500700D01*
X877700D01*
G01X891700D02*
X891100Y-500567D01*
X890500Y-500033D01*
X890100Y-499100D01*
X889900Y-498033D01*
X890100Y-496967D01*
X890500Y-496033D01*
X891100Y-495500D01*
X891700Y-495367D01*
X892300Y-495500D01*
X892900Y-496033D01*
X893300Y-496967D01*
X893400Y-498033D01*
X893300Y-499100D01*
X892900Y-500033D01*
X892300Y-500567D01*
X891700Y-500700D01*
G01X898300D02*
Y-495367D01*
G01Y-496433D02*
X898800Y-495900D01*
X899300Y-495500D01*
X900000Y-495367D01*
X900500Y-495500D01*
X901100Y-495900D01*
G01X913700Y-492700D02*
Y-500700D01*
X917700D01*
G01X922200Y-497100D02*
X925400D01*
X925100Y-496167D01*
X924600Y-495633D01*
X923900Y-495367D01*
X923200Y-495500D01*
X922600Y-495900D01*
X922200Y-496833D01*
X922000Y-497634D01*
Y-498433D01*
X922200Y-499233D01*
X922700Y-500033D01*
X923300Y-500567D01*
X924000Y-500700D01*
X924700Y-500433D01*
X925400Y-499634D01*
G01X933500Y-500700D02*
Y-495367D01*
G01Y-496300D02*
X933100Y-495767D01*
X932500Y-495500D01*
X931800Y-495367D01*
X931100Y-495633D01*
X930500Y-496167D01*
X930100Y-496967D01*
X929900Y-498033D01*
X930100Y-499100D01*
X930500Y-499900D01*
X931100Y-500433D01*
X931800Y-500700D01*
X932500Y-500567D01*
X933100Y-500167D01*
X933500Y-499634D01*
G01X941500Y-492700D02*
Y-500700D01*
G01Y-499500D02*
X941100Y-500167D01*
X940500Y-500567D01*
X939800Y-500700D01*
X939000Y-500433D01*
X938400Y-499767D01*
X938000Y-498967D01*
X937900Y-498033D01*
X938000Y-497100D01*
X938400Y-496300D01*
X939000Y-495633D01*
X939800Y-495367D01*
X940500Y-495500D01*
X941000Y-495767D01*
X941500Y-496300D01*
G01X953800Y-500700D02*
Y-492700D01*
X957600D01*
G01X956200Y-496567D02*
X953800D01*
G01X962300Y-500700D02*
Y-495367D01*
G01Y-496433D02*
X962800Y-495900D01*
X963300Y-495500D01*
X964000Y-495367D01*
X964500Y-495500D01*
X965100Y-495900D01*
G01X970200Y-497100D02*
X973400D01*
X973100Y-496167D01*
X972600Y-495633D01*
X971900Y-495367D01*
X971200Y-495500D01*
X970600Y-495900D01*
X970200Y-496833D01*
X970000Y-497634D01*
Y-498433D01*
X970200Y-499233D01*
X970700Y-500033D01*
X971300Y-500567D01*
X972000Y-500700D01*
X972700Y-500433D01*
X973400Y-499634D01*
G01X978200Y-497100D02*
X981400D01*
X981100Y-496167D01*
X980600Y-495633D01*
X979900Y-495367D01*
X979200Y-495500D01*
X978600Y-495900D01*
X978200Y-496833D01*
X978000Y-497634D01*
Y-498433D01*
X978200Y-499233D01*
X978700Y-500033D01*
X979300Y-500567D01*
X980000Y-500700D01*
X980700Y-500433D01*
X981400Y-499634D01*
G01X993600Y-500700D02*
Y-492700D01*
G01X997800D02*
Y-500700D01*
G01Y-496700D02*
X993600D01*
G01X1001200Y-500700D02*
X1003700Y-492700D01*
X1006200Y-500700D01*
G01X1005300Y-497900D02*
X1002100D01*
G01X1009600Y-499634D02*
X1010400Y-500300D01*
X1011300Y-500700D01*
X1012100D01*
X1012900Y-500300D01*
X1013500Y-499634D01*
X1013800Y-498700D01*
X1013600Y-497767D01*
X1013100Y-496967D01*
X1012200Y-496433D01*
X1011000Y-496167D01*
X1010300Y-495633D01*
X1010000Y-494700D01*
X1010200Y-493767D01*
X1010700Y-493100D01*
X1011400Y-492700D01*
X1012100D01*
X1012800Y-492967D01*
X1013400Y-493633D01*
G01X1017700Y-492700D02*
Y-500700D01*
X1021700D01*
G01X1028200Y-503367D02*
X1029200Y-502033D01*
X1029700Y-500700D01*
Y-495367D01*
X1029200Y-494033D01*
X1028200Y-492700D01*
G01X674200Y-480367D02*
X673200Y-479033D01*
X672700Y-477700D01*
Y-472367D01*
X673200Y-471033D01*
X674200Y-469700D01*
G01X680600Y-476634D02*
X681400Y-477300D01*
X682300Y-477700D01*
X683100D01*
X683900Y-477300D01*
X684500Y-476634D01*
X684800Y-475700D01*
X684600Y-474767D01*
X684100Y-473967D01*
X683200Y-473433D01*
X682000Y-473167D01*
X681300Y-472633D01*
X681000Y-471700D01*
X681200Y-470767D01*
X681700Y-470100D01*
X682400Y-469700D01*
X683100D01*
X683800Y-469967D01*
X684400Y-470633D01*
G01X689000Y-472367D02*
Y-476100D01*
X689400Y-477033D01*
X690000Y-477567D01*
X690700Y-477700D01*
X691400Y-477567D01*
X692000Y-477033D01*
X692400Y-476100D01*
G01Y-477700D02*
Y-472367D01*
G01X697300Y-477700D02*
Y-472367D01*
G01Y-473433D02*
X697800Y-472900D01*
X698300Y-472500D01*
X699000Y-472367D01*
X699500Y-472500D01*
X700100Y-472900D01*
G01X706100Y-477700D02*
Y-470900D01*
X706300Y-470233D01*
X706700Y-469833D01*
X707300Y-469700D01*
X707900Y-469967D01*
X708200Y-470633D01*
G01X707000Y-472900D02*
X705000D01*
G01X716500Y-477700D02*
Y-472367D01*
G01Y-473300D02*
X716100Y-472767D01*
X715500Y-472500D01*
X714800Y-472367D01*
X714100Y-472633D01*
X713500Y-473167D01*
X713100Y-473967D01*
X712900Y-475033D01*
X713100Y-476100D01*
X713500Y-476900D01*
X714100Y-477433D01*
X714800Y-477700D01*
X715500Y-477567D01*
X716100Y-477167D01*
X716500Y-476634D01*
G01X724300Y-473033D02*
X723600Y-472500D01*
X723000Y-472367D01*
X722200Y-472633D01*
X721600Y-473167D01*
X721200Y-474100D01*
X721100Y-475033D01*
X721200Y-475967D01*
X721600Y-476767D01*
X722200Y-477433D01*
X723000Y-477700D01*
X723700Y-477433D01*
X724300Y-476900D01*
G01X729200Y-474100D02*
X732400D01*
X732100Y-473167D01*
X731600Y-472633D01*
X730900Y-472367D01*
X730200Y-472500D01*
X729600Y-472900D01*
X729200Y-473833D01*
X729000Y-474634D01*
Y-475433D01*
X729200Y-476233D01*
X729700Y-477033D01*
X730300Y-477567D01*
X731000Y-477700D01*
X731700Y-477433D01*
X732400Y-476634D01*
G01X746700Y-469700D02*
Y-477700D01*
G01X745300Y-472367D02*
X748100D01*
G01X753300Y-477700D02*
Y-472367D01*
G01Y-473433D02*
X753800Y-472900D01*
X754300Y-472500D01*
X755000Y-472367D01*
X755500Y-472500D01*
X756100Y-472900D01*
G01X761200Y-474100D02*
X764400D01*
X764100Y-473167D01*
X763600Y-472633D01*
X762900Y-472367D01*
X762200Y-472500D01*
X761600Y-472900D01*
X761200Y-473833D01*
X761000Y-474634D01*
Y-475433D01*
X761200Y-476233D01*
X761700Y-477033D01*
X762300Y-477567D01*
X763000Y-477700D01*
X763700Y-477433D01*
X764400Y-476634D01*
G01X772500Y-477700D02*
Y-472367D01*
G01Y-473300D02*
X772100Y-472767D01*
X771500Y-472500D01*
X770800Y-472367D01*
X770100Y-472633D01*
X769500Y-473167D01*
X769100Y-473967D01*
X768900Y-475033D01*
X769100Y-476100D01*
X769500Y-476900D01*
X770100Y-477433D01*
X770800Y-477700D01*
X771500Y-477567D01*
X772100Y-477167D01*
X772500Y-476634D01*
G01X778700Y-469700D02*
Y-477700D01*
G01X777300Y-472367D02*
X780100D01*
G01X783700Y-477700D02*
Y-472367D01*
G01Y-473833D02*
X784000Y-473167D01*
X784500Y-472633D01*
X785200Y-472367D01*
X785900Y-472633D01*
X786400Y-473167D01*
X786700Y-473833D01*
Y-477700D01*
G01Y-473833D02*
X787000Y-473167D01*
X787500Y-472633D01*
X788200Y-472367D01*
X788900Y-472633D01*
X789400Y-473167D01*
X789700Y-473967D01*
Y-477700D01*
G01X793200Y-474100D02*
X796400D01*
X796100Y-473167D01*
X795600Y-472633D01*
X794900Y-472367D01*
X794200Y-472500D01*
X793600Y-472900D01*
X793200Y-473833D01*
X793000Y-474634D01*
Y-475433D01*
X793200Y-476233D01*
X793700Y-477033D01*
X794300Y-477567D01*
X795000Y-477700D01*
X795700Y-477433D01*
X796400Y-476634D01*
G01X801000Y-477700D02*
Y-472367D01*
G01Y-473700D02*
X801400Y-473033D01*
X802000Y-472500D01*
X802800Y-472367D01*
X803500Y-472500D01*
X804100Y-473033D01*
X804400Y-473967D01*
Y-477700D01*
G01X810700Y-469700D02*
Y-477700D01*
G01X809300Y-472367D02*
X812100D01*
G01X826700D02*
Y-477700D01*
G01Y-470233D02*
X826500Y-470100D01*
Y-469833D01*
X826700Y-469700D01*
X826900Y-469833D01*
Y-470100D01*
X826700Y-470233D01*
G01X833200Y-476767D02*
X833700Y-477300D01*
X834400Y-477700D01*
X835000D01*
X835600Y-477433D01*
X836000Y-477033D01*
X836200Y-476500D01*
X836100Y-475700D01*
X835700Y-475300D01*
X833900Y-474500D01*
X833500Y-473567D01*
X833700Y-472900D01*
X834100Y-472500D01*
X834700Y-472367D01*
X835300Y-472500D01*
X835900Y-472900D01*
G01X850700Y-472367D02*
Y-477700D01*
G01Y-470233D02*
X850500Y-470100D01*
Y-469833D01*
X850700Y-469700D01*
X850900Y-469833D01*
Y-470100D01*
X850700Y-470233D01*
G01X855700Y-477700D02*
Y-472367D01*
G01Y-473833D02*
X856000Y-473167D01*
X856500Y-472633D01*
X857200Y-472367D01*
X857900Y-472633D01*
X858400Y-473167D01*
X858700Y-473833D01*
Y-477700D01*
G01Y-473833D02*
X859000Y-473167D01*
X859500Y-472633D01*
X860200Y-472367D01*
X860900Y-472633D01*
X861400Y-473167D01*
X861700Y-473967D01*
Y-477700D01*
G01X863700D02*
Y-472367D01*
G01Y-473833D02*
X864000Y-473167D01*
X864500Y-472633D01*
X865200Y-472367D01*
X865900Y-472633D01*
X866400Y-473167D01*
X866700Y-473833D01*
Y-477700D01*
G01Y-473833D02*
X867000Y-473167D01*
X867500Y-472633D01*
X868200Y-472367D01*
X868900Y-472633D01*
X869400Y-473167D01*
X869700Y-473967D01*
Y-477700D01*
G01X873200Y-474100D02*
X876400D01*
X876100Y-473167D01*
X875600Y-472633D01*
X874900Y-472367D01*
X874200Y-472500D01*
X873600Y-472900D01*
X873200Y-473833D01*
X873000Y-474634D01*
Y-475433D01*
X873200Y-476233D01*
X873700Y-477033D01*
X874300Y-477567D01*
X875000Y-477700D01*
X875700Y-477433D01*
X876400Y-476634D01*
G01X881300Y-477700D02*
Y-472367D01*
G01Y-473433D02*
X881800Y-472900D01*
X882300Y-472500D01*
X883000Y-472367D01*
X883500Y-472500D01*
X884100Y-472900D01*
G01X889200Y-476767D02*
X889700Y-477300D01*
X890400Y-477700D01*
X891000D01*
X891600Y-477433D01*
X892000Y-477033D01*
X892200Y-476500D01*
X892100Y-475700D01*
X891700Y-475300D01*
X889900Y-474500D01*
X889500Y-473567D01*
X889700Y-472900D01*
X890100Y-472500D01*
X890700Y-472367D01*
X891300Y-472500D01*
X891900Y-472900D01*
G01X898700Y-472367D02*
Y-477700D01*
G01Y-470233D02*
X898500Y-470100D01*
Y-469833D01*
X898700Y-469700D01*
X898900Y-469833D01*
Y-470100D01*
X898700Y-470233D01*
G01X906700Y-477700D02*
X906100Y-477567D01*
X905500Y-477033D01*
X905100Y-476100D01*
X904900Y-475033D01*
X905100Y-473967D01*
X905500Y-473033D01*
X906100Y-472500D01*
X906700Y-472367D01*
X907300Y-472500D01*
X907900Y-473033D01*
X908300Y-473967D01*
X908400Y-475033D01*
X908300Y-476100D01*
X907900Y-477033D01*
X907300Y-477567D01*
X906700Y-477700D01*
G01X913000D02*
Y-472367D01*
G01Y-473700D02*
X913400Y-473033D01*
X914000Y-472500D01*
X914800Y-472367D01*
X915500Y-472500D01*
X916100Y-473033D01*
X916400Y-473967D01*
Y-477700D01*
G01X931300Y-473700D02*
X933300D01*
Y-476100D01*
X932700Y-476900D01*
X932000Y-477433D01*
X931000Y-477700D01*
X930000Y-477433D01*
X929300Y-476900D01*
X928700Y-476100D01*
X928300Y-475167D01*
X928100Y-474100D01*
Y-473167D01*
X928300Y-472367D01*
X928700Y-471433D01*
X929300Y-470633D01*
X929900Y-470100D01*
X930700Y-469700D01*
X931400D01*
X932200Y-469967D01*
X932800Y-470500D01*
G01X938700Y-477700D02*
X938100Y-477567D01*
X937500Y-477033D01*
X937100Y-476100D01*
X936900Y-475033D01*
X937100Y-473967D01*
X937500Y-473033D01*
X938100Y-472500D01*
X938700Y-472367D01*
X939300Y-472500D01*
X939900Y-473033D01*
X940300Y-473967D01*
X940400Y-475033D01*
X940300Y-476100D01*
X939900Y-477033D01*
X939300Y-477567D01*
X938700Y-477700D01*
G01X946700D02*
Y-469700D01*
G01X956500D02*
Y-477700D01*
G01Y-476500D02*
X956100Y-477167D01*
X955500Y-477567D01*
X954800Y-477700D01*
X954000Y-477433D01*
X953400Y-476767D01*
X953000Y-475967D01*
X952900Y-475033D01*
X953000Y-474100D01*
X953400Y-473300D01*
X954000Y-472633D01*
X954800Y-472367D01*
X955500Y-472500D01*
X956000Y-472767D01*
X956500Y-473300D01*
G01X962500Y-479167D02*
X962900Y-477433D01*
G01X972700Y-477700D02*
X968700D01*
Y-469700D01*
X972700D01*
G01X971100Y-473567D02*
X968700D01*
G01X977000Y-477700D02*
Y-472367D01*
G01Y-473700D02*
X977400Y-473033D01*
X978000Y-472500D01*
X978800Y-472367D01*
X979500Y-472500D01*
X980100Y-473033D01*
X980400Y-473967D01*
Y-477700D01*
G01X986700Y-469700D02*
Y-477700D01*
G01X985300Y-472367D02*
X988100D01*
G01X993200Y-474100D02*
X996400D01*
X996100Y-473167D01*
X995600Y-472633D01*
X994900Y-472367D01*
X994200Y-472500D01*
X993600Y-472900D01*
X993200Y-473833D01*
X993000Y-474634D01*
Y-475433D01*
X993200Y-476233D01*
X993700Y-477033D01*
X994300Y-477567D01*
X995000Y-477700D01*
X995700Y-477433D01*
X996400Y-476634D01*
G01X1001000Y-477700D02*
Y-469700D01*
G01X1004200Y-472367D02*
X1001000Y-475433D01*
G01X1002300Y-474233D02*
X1004400Y-477700D01*
G01X1018700D02*
X1018100Y-477567D01*
X1017500Y-477033D01*
X1017100Y-476100D01*
X1016900Y-475033D01*
X1017100Y-473967D01*
X1017500Y-473033D01*
X1018100Y-472500D01*
X1018700Y-472367D01*
X1019300Y-472500D01*
X1019900Y-473033D01*
X1020300Y-473967D01*
X1020400Y-475033D01*
X1020300Y-476100D01*
X1019900Y-477033D01*
X1019300Y-477567D01*
X1018700Y-477700D01*
G01X1025300D02*
Y-472367D01*
G01Y-473433D02*
X1025800Y-472900D01*
X1026300Y-472500D01*
X1027000Y-472367D01*
X1027500Y-472500D01*
X1028100Y-472900D01*
G01X1041500Y-469700D02*
X1043900D01*
G01X1042700D02*
Y-477700D01*
G01X1041500D02*
X1043900D01*
G01X1047700D02*
Y-472367D01*
G01Y-473833D02*
X1048000Y-473167D01*
X1048500Y-472633D01*
X1049200Y-472367D01*
X1049900Y-472633D01*
X1050400Y-473167D01*
X1050700Y-473833D01*
Y-477700D01*
G01Y-473833D02*
X1051000Y-473167D01*
X1051500Y-472633D01*
X1052200Y-472367D01*
X1052900Y-472633D01*
X1053400Y-473167D01*
X1053700Y-473967D01*
Y-477700D01*
G01X1056200D02*
X1058700Y-469700D01*
X1061200Y-477700D01*
G01X1060300Y-474900D02*
X1057100D01*
G01X1065300Y-479700D02*
X1066000Y-480233D01*
X1066800Y-480367D01*
X1067500Y-480233D01*
X1068100Y-479567D01*
X1068500Y-478633D01*
Y-472367D01*
G01Y-473433D02*
X1068100Y-472900D01*
X1067500Y-472500D01*
X1066800Y-472367D01*
X1066000Y-472633D01*
X1065500Y-473167D01*
X1065100Y-474100D01*
X1064900Y-475033D01*
X1065000Y-475833D01*
X1065400Y-476767D01*
X1066000Y-477433D01*
X1066800Y-477700D01*
X1067400Y-477567D01*
X1068100Y-477033D01*
X1068500Y-476500D01*
G01X1075200Y-480367D02*
X1076200Y-479033D01*
X1076700Y-477700D01*
Y-472367D01*
X1076200Y-471033D01*
X1075200Y-469700D01*
G01X674700Y-489700D02*
Y-481700D01*
X677100D01*
X677900Y-482100D01*
X678500Y-483033D01*
X678700Y-484100D01*
X678500Y-485167D01*
X678000Y-485967D01*
X677100Y-486367D01*
X674700D01*
G01X684700Y-481700D02*
Y-489700D01*
G01X682400Y-481700D02*
X687000D01*
G01X690600Y-489700D02*
Y-481700D01*
G01X694800D02*
Y-489700D01*
G01Y-485700D02*
X690600D01*
G01X707000Y-489700D02*
Y-481700D01*
G01Y-485567D02*
X707500Y-484900D01*
X708000Y-484500D01*
X708800Y-484367D01*
X709400Y-484500D01*
X710100Y-485033D01*
X710400Y-485833D01*
Y-489700D01*
G01X716700D02*
X716100Y-489567D01*
X715500Y-489033D01*
X715100Y-488100D01*
X714900Y-487033D01*
X715100Y-485967D01*
X715500Y-485033D01*
X716100Y-484500D01*
X716700Y-484367D01*
X717300Y-484500D01*
X717900Y-485033D01*
X718300Y-485967D01*
X718400Y-487033D01*
X718300Y-488100D01*
X717900Y-489033D01*
X717300Y-489567D01*
X716700Y-489700D01*
G01X724700D02*
Y-481700D01*
G01X731200Y-486100D02*
X734400D01*
X734100Y-485167D01*
X733600Y-484633D01*
X732900Y-484367D01*
X732200Y-484500D01*
X731600Y-484900D01*
X731200Y-485833D01*
X731000Y-486634D01*
Y-487433D01*
X731200Y-488233D01*
X731700Y-489033D01*
X732300Y-489567D01*
X733000Y-489700D01*
X733700Y-489433D01*
X734400Y-488634D01*
G01X748100Y-489700D02*
Y-482900D01*
X748300Y-482233D01*
X748700Y-481833D01*
X749300Y-481700D01*
X749900Y-481967D01*
X750200Y-482633D01*
G01X749000Y-484900D02*
X747000D01*
G01X756700Y-489700D02*
X756100Y-489567D01*
X755500Y-489033D01*
X755100Y-488100D01*
X754900Y-487033D01*
X755100Y-485967D01*
X755500Y-485033D01*
X756100Y-484500D01*
X756700Y-484367D01*
X757300Y-484500D01*
X757900Y-485033D01*
X758300Y-485967D01*
X758400Y-487033D01*
X758300Y-488100D01*
X757900Y-489033D01*
X757300Y-489567D01*
X756700Y-489700D01*
G01X763300D02*
Y-484367D01*
G01Y-485433D02*
X763800Y-484900D01*
X764300Y-484500D01*
X765000Y-484367D01*
X765500Y-484500D01*
X766100Y-484900D01*
G01X782300Y-485033D02*
X781600Y-484500D01*
X781000Y-484367D01*
X780200Y-484633D01*
X779600Y-485167D01*
X779200Y-486100D01*
X779100Y-487033D01*
X779200Y-487967D01*
X779600Y-488767D01*
X780200Y-489433D01*
X781000Y-489700D01*
X781700Y-489433D01*
X782300Y-488900D01*
G01X788700Y-489700D02*
X788100Y-489567D01*
X787500Y-489033D01*
X787100Y-488100D01*
X786900Y-487033D01*
X787100Y-485967D01*
X787500Y-485033D01*
X788100Y-484500D01*
X788700Y-484367D01*
X789300Y-484500D01*
X789900Y-485033D01*
X790300Y-485967D01*
X790400Y-487033D01*
X790300Y-488100D01*
X789900Y-489033D01*
X789300Y-489567D01*
X788700Y-489700D01*
G01X793700D02*
Y-484367D01*
G01Y-485833D02*
X794000Y-485167D01*
X794500Y-484633D01*
X795200Y-484367D01*
X795900Y-484633D01*
X796400Y-485167D01*
X796700Y-485833D01*
Y-489700D01*
G01Y-485833D02*
X797000Y-485167D01*
X797500Y-484633D01*
X798200Y-484367D01*
X798900Y-484633D01*
X799400Y-485167D01*
X799700Y-485967D01*
Y-489700D01*
G01X802900Y-492367D02*
Y-484367D01*
G01Y-485567D02*
X803400Y-484900D01*
X803900Y-484500D01*
X804700Y-484367D01*
X805400Y-484500D01*
X806100Y-485167D01*
X806400Y-486100D01*
X806500Y-487033D01*
X806400Y-487967D01*
X806100Y-488900D01*
X805500Y-489433D01*
X804700Y-489700D01*
X804000Y-489567D01*
X803300Y-489167D01*
X802900Y-488634D01*
G01X812700Y-489700D02*
X812100Y-489567D01*
X811500Y-489033D01*
X811100Y-488100D01*
X810900Y-487033D01*
X811100Y-485967D01*
X811500Y-485033D01*
X812100Y-484500D01*
X812700Y-484367D01*
X813300Y-484500D01*
X813900Y-485033D01*
X814300Y-485967D01*
X814400Y-487033D01*
X814300Y-488100D01*
X813900Y-489033D01*
X813300Y-489567D01*
X812700Y-489700D01*
G01X819000D02*
Y-484367D01*
G01Y-485700D02*
X819400Y-485033D01*
X820000Y-484500D01*
X820800Y-484367D01*
X821500Y-484500D01*
X822100Y-485033D01*
X822400Y-485967D01*
Y-489700D01*
G01X827200Y-486100D02*
X830400D01*
X830100Y-485167D01*
X829600Y-484633D01*
X828900Y-484367D01*
X828200Y-484500D01*
X827600Y-484900D01*
X827200Y-485833D01*
X827000Y-486634D01*
Y-487433D01*
X827200Y-488233D01*
X827700Y-489033D01*
X828300Y-489567D01*
X829000Y-489700D01*
X829700Y-489433D01*
X830400Y-488634D01*
G01X835000Y-489700D02*
Y-484367D01*
G01Y-485700D02*
X835400Y-485033D01*
X836000Y-484500D01*
X836800Y-484367D01*
X837500Y-484500D01*
X838100Y-485033D01*
X838400Y-485967D01*
Y-489700D01*
G01X844700Y-481700D02*
Y-489700D01*
G01X843300Y-484367D02*
X846100D01*
G01X860200Y-492367D02*
X859200Y-491033D01*
X858700Y-489700D01*
Y-484367D01*
X859200Y-483033D01*
X860200Y-481700D01*
G01X868700Y-489700D02*
Y-481700D01*
X867500Y-483300D01*
G01Y-489700D02*
X869900D01*
G01X874800Y-486367D02*
X875500Y-485433D01*
X876100Y-484900D01*
X876900Y-484633D01*
X877600Y-484900D01*
X878100Y-485433D01*
X878500Y-486233D01*
X878600Y-487167D01*
X878500Y-487967D01*
X878100Y-488767D01*
X877500Y-489433D01*
X876800Y-489700D01*
X876000Y-489433D01*
X875300Y-488634D01*
X874900Y-487433D01*
X874800Y-486100D01*
X875000Y-484367D01*
X875300Y-483433D01*
X875800Y-482500D01*
X876500Y-481833D01*
X877200Y-481700D01*
X877900Y-481967D01*
X878400Y-482633D01*
G01X881700Y-489700D02*
Y-484367D01*
G01Y-485833D02*
X882000Y-485167D01*
X882500Y-484633D01*
X883200Y-484367D01*
X883900Y-484633D01*
X884400Y-485167D01*
X884700Y-485833D01*
Y-489700D01*
G01Y-485833D02*
X885000Y-485167D01*
X885500Y-484633D01*
X886200Y-484367D01*
X886900Y-484633D01*
X887400Y-485167D01*
X887700Y-485967D01*
Y-489700D01*
G01X892700Y-484367D02*
Y-489700D01*
G01Y-482233D02*
X892500Y-482100D01*
Y-481833D01*
X892700Y-481700D01*
X892900Y-481833D01*
Y-482100D01*
X892700Y-482233D01*
G01X900700Y-489700D02*
Y-481700D01*
G01X918700Y-489700D02*
X914700Y-487033D01*
X918700Y-484367D01*
G01X931200Y-488767D02*
X931700Y-489300D01*
X932400Y-489700D01*
X933000D01*
X933600Y-489433D01*
X934000Y-489033D01*
X934200Y-488500D01*
X934100Y-487700D01*
X933700Y-487300D01*
X931900Y-486500D01*
X931500Y-485567D01*
X931700Y-484900D01*
X932100Y-484500D01*
X932700Y-484367D01*
X933300Y-484500D01*
X933900Y-484900D01*
G01X940700Y-484367D02*
Y-489700D01*
G01Y-482233D02*
X940500Y-482100D01*
Y-481833D01*
X940700Y-481700D01*
X940900Y-481833D01*
Y-482100D01*
X940700Y-482233D01*
G01X947200Y-484367D02*
X950200D01*
X947200Y-489700D01*
X950200D01*
G01X955200Y-486100D02*
X958400D01*
X958100Y-485167D01*
X957600Y-484633D01*
X956900Y-484367D01*
X956200Y-484500D01*
X955600Y-484900D01*
X955200Y-485833D01*
X955000Y-486634D01*
Y-487433D01*
X955200Y-488233D01*
X955700Y-489033D01*
X956300Y-489567D01*
X957000Y-489700D01*
X957700Y-489433D01*
X958400Y-488634D01*
G01X974700Y-489700D02*
X970700Y-487033D01*
X974700Y-484367D01*
G01X980700Y-489700D02*
Y-481700D01*
X979500Y-483300D01*
G01Y-489700D02*
X981900D01*
G01X987000Y-488767D02*
X987700Y-489433D01*
X988500Y-489700D01*
X989300Y-489433D01*
X990000Y-488634D01*
X990500Y-487433D01*
X990700Y-486233D01*
Y-484767D01*
X990500Y-483567D01*
X990000Y-482500D01*
X989400Y-481967D01*
X988700Y-481700D01*
X987900Y-481967D01*
X987300Y-482500D01*
X986900Y-483300D01*
X986700Y-484367D01*
X986900Y-485300D01*
X987400Y-486233D01*
X988000Y-486767D01*
X988700Y-486900D01*
X989500Y-486634D01*
X990100Y-485967D01*
X990700Y-484767D01*
G01X996500Y-489700D02*
X996700Y-487967D01*
X997000Y-486500D01*
X997400Y-485167D01*
X997900Y-483700D01*
X998700Y-481700D01*
X994700D01*
G01X1001700Y-489700D02*
Y-484367D01*
G01Y-485833D02*
X1002000Y-485167D01*
X1002500Y-484633D01*
X1003200Y-484367D01*
X1003900Y-484633D01*
X1004400Y-485167D01*
X1004700Y-485833D01*
Y-489700D01*
G01Y-485833D02*
X1005000Y-485167D01*
X1005500Y-484633D01*
X1006200Y-484367D01*
X1006900Y-484633D01*
X1007400Y-485167D01*
X1007700Y-485967D01*
Y-489700D01*
G01X1012700Y-484367D02*
Y-489700D01*
G01Y-482233D02*
X1012500Y-482100D01*
Y-481833D01*
X1012700Y-481700D01*
X1012900Y-481833D01*
Y-482100D01*
X1012700Y-482233D01*
G01X1020700Y-489700D02*
Y-481700D01*
G01X1029200Y-492367D02*
X1030200Y-491033D01*
X1030700Y-489700D01*
Y-484367D01*
X1030200Y-483033D01*
X1029200Y-481700D01*
G01X674200Y-464700D02*
Y-456700D01*
X676600D01*
X677400Y-457100D01*
X678000Y-458033D01*
X678200Y-459100D01*
X678000Y-460167D01*
X677500Y-460967D01*
X676600Y-461367D01*
X674200D01*
G01X684200Y-456700D02*
Y-464700D01*
G01X681900Y-456700D02*
X686500D01*
G01X690100Y-464700D02*
Y-456700D01*
G01X694300D02*
Y-464700D01*
G01Y-460700D02*
X690100D01*
G01X706500Y-464700D02*
Y-456700D01*
G01Y-460567D02*
X707000Y-459900D01*
X707500Y-459500D01*
X708300Y-459367D01*
X708900Y-459500D01*
X709600Y-460033D01*
X709900Y-460833D01*
Y-464700D01*
G01X716200D02*
X715600Y-464567D01*
X715000Y-464033D01*
X714600Y-463100D01*
X714400Y-462033D01*
X714600Y-460967D01*
X715000Y-460033D01*
X715600Y-459500D01*
X716200Y-459367D01*
X716800Y-459500D01*
X717400Y-460033D01*
X717800Y-460967D01*
X717900Y-462033D01*
X717800Y-463100D01*
X717400Y-464033D01*
X716800Y-464567D01*
X716200Y-464700D01*
G01X724200D02*
Y-456700D01*
G01X730700Y-461100D02*
X733900D01*
X733600Y-460167D01*
X733100Y-459633D01*
X732400Y-459367D01*
X731700Y-459500D01*
X731100Y-459900D01*
X730700Y-460833D01*
X730500Y-461634D01*
Y-462433D01*
X730700Y-463233D01*
X731200Y-464033D01*
X731800Y-464567D01*
X732500Y-464700D01*
X733200Y-464433D01*
X733900Y-463634D01*
G01X747600Y-464700D02*
Y-457900D01*
X747800Y-457233D01*
X748200Y-456833D01*
X748800Y-456700D01*
X749400Y-456967D01*
X749700Y-457633D01*
G01X748500Y-459900D02*
X746500D01*
G01X756200Y-464700D02*
X755600Y-464567D01*
X755000Y-464033D01*
X754600Y-463100D01*
X754400Y-462033D01*
X754600Y-460967D01*
X755000Y-460033D01*
X755600Y-459500D01*
X756200Y-459367D01*
X756800Y-459500D01*
X757400Y-460033D01*
X757800Y-460967D01*
X757900Y-462033D01*
X757800Y-463100D01*
X757400Y-464033D01*
X756800Y-464567D01*
X756200Y-464700D01*
G01X762800D02*
Y-459367D01*
G01Y-460433D02*
X763300Y-459900D01*
X763800Y-459500D01*
X764500Y-459367D01*
X765000Y-459500D01*
X765600Y-459900D01*
G01X781800Y-460033D02*
X781100Y-459500D01*
X780500Y-459367D01*
X779700Y-459633D01*
X779100Y-460167D01*
X778700Y-461100D01*
X778600Y-462033D01*
X778700Y-462967D01*
X779100Y-463767D01*
X779700Y-464433D01*
X780500Y-464700D01*
X781200Y-464433D01*
X781800Y-463900D01*
G01X788200Y-464700D02*
X787600Y-464567D01*
X787000Y-464033D01*
X786600Y-463100D01*
X786400Y-462033D01*
X786600Y-460967D01*
X787000Y-460033D01*
X787600Y-459500D01*
X788200Y-459367D01*
X788800Y-459500D01*
X789400Y-460033D01*
X789800Y-460967D01*
X789900Y-462033D01*
X789800Y-463100D01*
X789400Y-464033D01*
X788800Y-464567D01*
X788200Y-464700D01*
G01X793200D02*
Y-459367D01*
G01Y-460833D02*
X793500Y-460167D01*
X794000Y-459633D01*
X794700Y-459367D01*
X795400Y-459633D01*
X795900Y-460167D01*
X796200Y-460833D01*
Y-464700D01*
G01Y-460833D02*
X796500Y-460167D01*
X797000Y-459633D01*
X797700Y-459367D01*
X798400Y-459633D01*
X798900Y-460167D01*
X799200Y-460967D01*
Y-464700D01*
G01X802400Y-467367D02*
Y-459367D01*
G01Y-460567D02*
X802900Y-459900D01*
X803400Y-459500D01*
X804200Y-459367D01*
X804900Y-459500D01*
X805600Y-460167D01*
X805900Y-461100D01*
X806000Y-462033D01*
X805900Y-462967D01*
X805600Y-463900D01*
X805000Y-464433D01*
X804200Y-464700D01*
X803500Y-464567D01*
X802800Y-464167D01*
X802400Y-463634D01*
G01X812200Y-464700D02*
X811600Y-464567D01*
X811000Y-464033D01*
X810600Y-463100D01*
X810400Y-462033D01*
X810600Y-460967D01*
X811000Y-460033D01*
X811600Y-459500D01*
X812200Y-459367D01*
X812800Y-459500D01*
X813400Y-460033D01*
X813800Y-460967D01*
X813900Y-462033D01*
X813800Y-463100D01*
X813400Y-464033D01*
X812800Y-464567D01*
X812200Y-464700D01*
G01X818500D02*
Y-459367D01*
G01Y-460700D02*
X818900Y-460033D01*
X819500Y-459500D01*
X820300Y-459367D01*
X821000Y-459500D01*
X821600Y-460033D01*
X821900Y-460967D01*
Y-464700D01*
G01X826700Y-461100D02*
X829900D01*
X829600Y-460167D01*
X829100Y-459633D01*
X828400Y-459367D01*
X827700Y-459500D01*
X827100Y-459900D01*
X826700Y-460833D01*
X826500Y-461634D01*
Y-462433D01*
X826700Y-463233D01*
X827200Y-464033D01*
X827800Y-464567D01*
X828500Y-464700D01*
X829200Y-464433D01*
X829900Y-463634D01*
G01X834500Y-464700D02*
Y-459367D01*
G01Y-460700D02*
X834900Y-460033D01*
X835500Y-459500D01*
X836300Y-459367D01*
X837000Y-459500D01*
X837600Y-460033D01*
X837900Y-460967D01*
Y-464700D01*
G01X844200Y-456700D02*
Y-464700D01*
G01X842800Y-459367D02*
X845600D01*
G01X859700Y-467367D02*
X858700Y-466033D01*
X858200Y-464700D01*
Y-459367D01*
X858700Y-458033D01*
X859700Y-456700D01*
G01X868200Y-464700D02*
Y-456700D01*
X867000Y-458300D01*
G01Y-464700D02*
X869400D01*
G01X874300Y-461367D02*
X875000Y-460433D01*
X875600Y-459900D01*
X876400Y-459633D01*
X877100Y-459900D01*
X877600Y-460433D01*
X878000Y-461233D01*
X878100Y-462167D01*
X878000Y-462967D01*
X877600Y-463767D01*
X877000Y-464433D01*
X876300Y-464700D01*
X875500Y-464433D01*
X874800Y-463634D01*
X874400Y-462433D01*
X874300Y-461100D01*
X874500Y-459367D01*
X874800Y-458433D01*
X875300Y-457500D01*
X876000Y-456833D01*
X876700Y-456700D01*
X877400Y-456967D01*
X877900Y-457633D01*
G01X881200Y-464700D02*
Y-459367D01*
G01Y-460833D02*
X881500Y-460167D01*
X882000Y-459633D01*
X882700Y-459367D01*
X883400Y-459633D01*
X883900Y-460167D01*
X884200Y-460833D01*
Y-464700D01*
G01Y-460833D02*
X884500Y-460167D01*
X885000Y-459633D01*
X885700Y-459367D01*
X886400Y-459633D01*
X886900Y-460167D01*
X887200Y-460967D01*
Y-464700D01*
G01X892200Y-459367D02*
Y-464700D01*
G01Y-457233D02*
X892000Y-457100D01*
Y-456833D01*
X892200Y-456700D01*
X892400Y-456833D01*
Y-457100D01*
X892200Y-457233D01*
G01X900200Y-464700D02*
Y-456700D01*
G01X918200Y-464700D02*
X914200Y-462033D01*
X918200Y-459367D01*
G01X930700Y-463767D02*
X931200Y-464300D01*
X931900Y-464700D01*
X932500D01*
X933100Y-464433D01*
X933500Y-464033D01*
X933700Y-463500D01*
X933600Y-462700D01*
X933200Y-462300D01*
X931400Y-461500D01*
X931000Y-460567D01*
X931200Y-459900D01*
X931600Y-459500D01*
X932200Y-459367D01*
X932800Y-459500D01*
X933400Y-459900D01*
G01X940200Y-459367D02*
Y-464700D01*
G01Y-457233D02*
X940000Y-457100D01*
Y-456833D01*
X940200Y-456700D01*
X940400Y-456833D01*
Y-457100D01*
X940200Y-457233D01*
G01X946700Y-459367D02*
X949700D01*
X946700Y-464700D01*
X949700D01*
G01X954700Y-461100D02*
X957900D01*
X957600Y-460167D01*
X957100Y-459633D01*
X956400Y-459367D01*
X955700Y-459500D01*
X955100Y-459900D01*
X954700Y-460833D01*
X954500Y-461634D01*
Y-462433D01*
X954700Y-463233D01*
X955200Y-464033D01*
X955800Y-464567D01*
X956500Y-464700D01*
X957200Y-464433D01*
X957900Y-463634D01*
G01X974200Y-464700D02*
X970200Y-462033D01*
X974200Y-459367D01*
G01X980200Y-464700D02*
Y-456700D01*
X979000Y-458300D01*
G01Y-464700D02*
X981400D01*
G01X986500Y-463767D02*
X987200Y-464433D01*
X988000Y-464700D01*
X988800Y-464433D01*
X989500Y-463634D01*
X990000Y-462433D01*
X990200Y-461233D01*
Y-459767D01*
X990000Y-458567D01*
X989500Y-457500D01*
X988900Y-456967D01*
X988200Y-456700D01*
X987400Y-456967D01*
X986800Y-457500D01*
X986400Y-458300D01*
X986200Y-459367D01*
X986400Y-460300D01*
X986900Y-461233D01*
X987500Y-461767D01*
X988200Y-461900D01*
X989000Y-461634D01*
X989600Y-460967D01*
X990200Y-459767D01*
G01X996000Y-464700D02*
X996200Y-462967D01*
X996500Y-461500D01*
X996900Y-460167D01*
X997400Y-458700D01*
X998200Y-456700D01*
X994200D01*
G01X1001200Y-464700D02*
Y-459367D01*
G01Y-460833D02*
X1001500Y-460167D01*
X1002000Y-459633D01*
X1002700Y-459367D01*
X1003400Y-459633D01*
X1003900Y-460167D01*
X1004200Y-460833D01*
Y-464700D01*
G01Y-460833D02*
X1004500Y-460167D01*
X1005000Y-459633D01*
X1005700Y-459367D01*
X1006400Y-459633D01*
X1006900Y-460167D01*
X1007200Y-460967D01*
Y-464700D01*
G01X1012200Y-459367D02*
Y-464700D01*
G01Y-457233D02*
X1012000Y-457100D01*
Y-456833D01*
X1012200Y-456700D01*
X1012400Y-456833D01*
Y-457100D01*
X1012200Y-457233D01*
G01X1020200Y-464700D02*
Y-456700D01*
G01X1028700Y-467367D02*
X1029700Y-466033D01*
X1030200Y-464700D01*
Y-459367D01*
X1029700Y-458033D01*
X1028700Y-456700D01*
G01X673700Y-444200D02*
Y-452200D01*
X677700D01*
G01X685500D02*
Y-446867D01*
G01Y-447800D02*
X685100Y-447267D01*
X684500Y-447000D01*
X683800Y-446867D01*
X683100Y-447133D01*
X682500Y-447667D01*
X682100Y-448467D01*
X681900Y-449533D01*
X682100Y-450600D01*
X682500Y-451400D01*
X683100Y-451933D01*
X683800Y-452200D01*
X684500Y-452067D01*
X685100Y-451667D01*
X685500Y-451134D01*
G01X690200Y-451267D02*
X690700Y-451800D01*
X691400Y-452200D01*
X692000D01*
X692600Y-451933D01*
X693000Y-451533D01*
X693200Y-451000D01*
X693100Y-450200D01*
X692700Y-449800D01*
X690900Y-449000D01*
X690500Y-448067D01*
X690700Y-447400D01*
X691100Y-447000D01*
X691700Y-446867D01*
X692300Y-447000D01*
X692900Y-447400D01*
G01X698200Y-448600D02*
X701400D01*
X701100Y-447667D01*
X700600Y-447133D01*
X699900Y-446867D01*
X699200Y-447000D01*
X698600Y-447400D01*
X698200Y-448333D01*
X698000Y-449134D01*
Y-449933D01*
X698200Y-450733D01*
X698700Y-451533D01*
X699300Y-452067D01*
X700000Y-452200D01*
X700700Y-451933D01*
X701400Y-451134D01*
G01X706300Y-452200D02*
Y-446867D01*
G01Y-447933D02*
X706800Y-447400D01*
X707300Y-447000D01*
X708000Y-446867D01*
X708500Y-447000D01*
X709100Y-447400D01*
G01X721900Y-446867D02*
X723700Y-452200D01*
X725500Y-446867D01*
G01X731700D02*
Y-452200D01*
G01Y-444733D02*
X731500Y-444600D01*
Y-444333D01*
X731700Y-444200D01*
X731900Y-444333D01*
Y-444600D01*
X731700Y-444733D01*
G01X741500Y-452200D02*
Y-446867D01*
G01Y-447800D02*
X741100Y-447267D01*
X740500Y-447000D01*
X739800Y-446867D01*
X739100Y-447133D01*
X738500Y-447667D01*
X738100Y-448467D01*
X737900Y-449533D01*
X738100Y-450600D01*
X738500Y-451400D01*
X739100Y-451933D01*
X739800Y-452200D01*
X740500Y-452067D01*
X741100Y-451667D01*
X741500Y-451134D01*
G01X754000Y-452200D02*
Y-444200D01*
G01Y-448067D02*
X754500Y-447400D01*
X755000Y-447000D01*
X755800Y-446867D01*
X756400Y-447000D01*
X757100Y-447533D01*
X757400Y-448333D01*
Y-452200D01*
G01X763700D02*
X763100Y-452067D01*
X762500Y-451533D01*
X762100Y-450600D01*
X761900Y-449533D01*
X762100Y-448467D01*
X762500Y-447533D01*
X763100Y-447000D01*
X763700Y-446867D01*
X764300Y-447000D01*
X764900Y-447533D01*
X765300Y-448467D01*
X765400Y-449533D01*
X765300Y-450600D01*
X764900Y-451533D01*
X764300Y-452067D01*
X763700Y-452200D01*
G01X771700D02*
Y-444200D01*
G01X778200Y-448600D02*
X781400D01*
X781100Y-447667D01*
X780600Y-447133D01*
X779900Y-446867D01*
X779200Y-447000D01*
X778600Y-447400D01*
X778200Y-448333D01*
X778000Y-449134D01*
Y-449933D01*
X778200Y-450733D01*
X778700Y-451533D01*
X779300Y-452067D01*
X780000Y-452200D01*
X780700Y-451933D01*
X781400Y-451134D01*
G01X795200Y-454867D02*
X794200Y-453533D01*
X793700Y-452200D01*
Y-446867D01*
X794200Y-445533D01*
X795200Y-444200D01*
G01X801900Y-452200D02*
Y-444200D01*
G01Y-448200D02*
X802400Y-447400D01*
X803000Y-447000D01*
X803600Y-446867D01*
X804500Y-447133D01*
X805100Y-447667D01*
X805500Y-448600D01*
Y-449667D01*
X805300Y-450733D01*
X804900Y-451533D01*
X804200Y-452067D01*
X803600Y-452200D01*
X803000Y-452067D01*
X802400Y-451667D01*
X801900Y-451000D01*
G01X810200Y-448600D02*
X813400D01*
X813100Y-447667D01*
X812600Y-447133D01*
X811900Y-446867D01*
X811200Y-447000D01*
X810600Y-447400D01*
X810200Y-448333D01*
X810000Y-449134D01*
Y-449933D01*
X810200Y-450733D01*
X810700Y-451533D01*
X811300Y-452067D01*
X812000Y-452200D01*
X812700Y-451933D01*
X813400Y-451134D01*
G01X819100Y-452200D02*
Y-445400D01*
X819300Y-444733D01*
X819700Y-444333D01*
X820300Y-444200D01*
X820900Y-444467D01*
X821200Y-445133D01*
G01X820000Y-447400D02*
X818000D01*
G01X827700Y-452200D02*
X827100Y-452067D01*
X826500Y-451533D01*
X826100Y-450600D01*
X825900Y-449533D01*
X826100Y-448467D01*
X826500Y-447533D01*
X827100Y-447000D01*
X827700Y-446867D01*
X828300Y-447000D01*
X828900Y-447533D01*
X829300Y-448467D01*
X829400Y-449533D01*
X829300Y-450600D01*
X828900Y-451533D01*
X828300Y-452067D01*
X827700Y-452200D01*
G01X834300D02*
Y-446867D01*
G01Y-447933D02*
X834800Y-447400D01*
X835300Y-447000D01*
X836000Y-446867D01*
X836500Y-447000D01*
X837100Y-447400D01*
G01X842200Y-448600D02*
X845400D01*
X845100Y-447667D01*
X844600Y-447133D01*
X843900Y-446867D01*
X843200Y-447000D01*
X842600Y-447400D01*
X842200Y-448333D01*
X842000Y-449134D01*
Y-449933D01*
X842200Y-450733D01*
X842700Y-451533D01*
X843300Y-452067D01*
X844000Y-452200D01*
X844700Y-451933D01*
X845400Y-451134D01*
G01X859700Y-444200D02*
Y-452200D01*
G01X858300Y-446867D02*
X861100D01*
G01X866000Y-452200D02*
Y-444200D01*
G01Y-448067D02*
X866500Y-447400D01*
X867000Y-447000D01*
X867800Y-446867D01*
X868400Y-447000D01*
X869100Y-447533D01*
X869400Y-448333D01*
Y-452200D01*
G01X874200Y-448600D02*
X877400D01*
X877100Y-447667D01*
X876600Y-447133D01*
X875900Y-446867D01*
X875200Y-447000D01*
X874600Y-447400D01*
X874200Y-448333D01*
X874000Y-449134D01*
Y-449933D01*
X874200Y-450733D01*
X874700Y-451533D01*
X875300Y-452067D01*
X876000Y-452200D01*
X876700Y-451933D01*
X877400Y-451134D01*
G01X893300Y-447533D02*
X892600Y-447000D01*
X892000Y-446867D01*
X891200Y-447133D01*
X890600Y-447667D01*
X890200Y-448600D01*
X890100Y-449533D01*
X890200Y-450467D01*
X890600Y-451267D01*
X891200Y-451933D01*
X892000Y-452200D01*
X892700Y-451933D01*
X893300Y-451400D01*
G01X899700Y-452200D02*
X899100Y-452067D01*
X898500Y-451533D01*
X898100Y-450600D01*
X897900Y-449533D01*
X898100Y-448467D01*
X898500Y-447533D01*
X899100Y-447000D01*
X899700Y-446867D01*
X900300Y-447000D01*
X900900Y-447533D01*
X901300Y-448467D01*
X901400Y-449533D01*
X901300Y-450600D01*
X900900Y-451533D01*
X900300Y-452067D01*
X899700Y-452200D01*
G01X905900Y-454867D02*
Y-446867D01*
G01Y-448067D02*
X906400Y-447400D01*
X906900Y-447000D01*
X907700Y-446867D01*
X908400Y-447000D01*
X909100Y-447667D01*
X909400Y-448600D01*
X909500Y-449533D01*
X909400Y-450467D01*
X909100Y-451400D01*
X908500Y-451933D01*
X907700Y-452200D01*
X907000Y-452067D01*
X906300Y-451667D01*
X905900Y-451134D01*
G01X913900Y-454867D02*
Y-446867D01*
G01Y-448067D02*
X914400Y-447400D01*
X914900Y-447000D01*
X915700Y-446867D01*
X916400Y-447000D01*
X917100Y-447667D01*
X917400Y-448600D01*
X917500Y-449533D01*
X917400Y-450467D01*
X917100Y-451400D01*
X916500Y-451933D01*
X915700Y-452200D01*
X915000Y-452067D01*
X914300Y-451667D01*
X913900Y-451134D01*
G01X922200Y-448600D02*
X925400D01*
X925100Y-447667D01*
X924600Y-447133D01*
X923900Y-446867D01*
X923200Y-447000D01*
X922600Y-447400D01*
X922200Y-448333D01*
X922000Y-449134D01*
Y-449933D01*
X922200Y-450733D01*
X922700Y-451533D01*
X923300Y-452067D01*
X924000Y-452200D01*
X924700Y-451933D01*
X925400Y-451134D01*
G01X930300Y-452200D02*
Y-446867D01*
G01Y-447933D02*
X930800Y-447400D01*
X931300Y-447000D01*
X932000Y-446867D01*
X932500Y-447000D01*
X933100Y-447400D01*
G01X945900Y-454867D02*
Y-446867D01*
G01Y-448067D02*
X946400Y-447400D01*
X946900Y-447000D01*
X947700Y-446867D01*
X948400Y-447000D01*
X949100Y-447667D01*
X949400Y-448600D01*
X949500Y-449533D01*
X949400Y-450467D01*
X949100Y-451400D01*
X948500Y-451933D01*
X947700Y-452200D01*
X947000Y-452067D01*
X946300Y-451667D01*
X945900Y-451134D01*
G01X955700Y-452200D02*
Y-444200D01*
G01X965500Y-452200D02*
Y-446867D01*
G01Y-447800D02*
X965100Y-447267D01*
X964500Y-447000D01*
X963800Y-446867D01*
X963100Y-447133D01*
X962500Y-447667D01*
X962100Y-448467D01*
X961900Y-449533D01*
X962100Y-450600D01*
X962500Y-451400D01*
X963100Y-451933D01*
X963800Y-452200D01*
X964500Y-452067D01*
X965100Y-451667D01*
X965500Y-451134D01*
G01X971700Y-444200D02*
Y-452200D01*
G01X970300Y-446867D02*
X973100D01*
G01X979700D02*
Y-452200D01*
G01Y-444733D02*
X979500Y-444600D01*
Y-444333D01*
X979700Y-444200D01*
X979900Y-444333D01*
Y-444600D01*
X979700Y-444733D01*
G01X986000Y-452200D02*
Y-446867D01*
G01Y-448200D02*
X986400Y-447533D01*
X987000Y-447000D01*
X987800Y-446867D01*
X988500Y-447000D01*
X989100Y-447533D01*
X989400Y-448467D01*
Y-452200D01*
G01X994300Y-454200D02*
X995000Y-454733D01*
X995800Y-454867D01*
X996500Y-454733D01*
X997100Y-454067D01*
X997500Y-453133D01*
Y-446867D01*
G01Y-447933D02*
X997100Y-447400D01*
X996500Y-447000D01*
X995800Y-446867D01*
X995000Y-447133D01*
X994500Y-447667D01*
X994100Y-448600D01*
X993900Y-449533D01*
X994000Y-450333D01*
X994400Y-451267D01*
X995000Y-451933D01*
X995800Y-452200D01*
X996400Y-452067D01*
X997100Y-451533D01*
X997500Y-451000D01*
G01X1004200Y-454867D02*
X1005200Y-453533D01*
X1005700Y-452200D01*
Y-446867D01*
X1005200Y-445533D01*
X1004200Y-444200D01*
G01X673200Y-431700D02*
X675700Y-439700D01*
X678200Y-431700D01*
G01X683700Y-434367D02*
Y-439700D01*
G01Y-432233D02*
X683500Y-432100D01*
Y-431833D01*
X683700Y-431700D01*
X683900Y-431833D01*
Y-432100D01*
X683700Y-432233D01*
G01X693500Y-439700D02*
Y-434367D01*
G01Y-435300D02*
X693100Y-434767D01*
X692500Y-434500D01*
X691800Y-434367D01*
X691100Y-434633D01*
X690500Y-435167D01*
X690100Y-435967D01*
X689900Y-437033D01*
X690100Y-438100D01*
X690500Y-438900D01*
X691100Y-439433D01*
X691800Y-439700D01*
X692500Y-439567D01*
X693100Y-439167D01*
X693500Y-438634D01*
G01X705600Y-439700D02*
Y-431700D01*
G01X709800D02*
Y-439700D01*
G01Y-435700D02*
X705600D01*
G01X715700Y-439700D02*
X715100Y-439567D01*
X714500Y-439033D01*
X714100Y-438100D01*
X713900Y-437033D01*
X714100Y-435967D01*
X714500Y-435033D01*
X715100Y-434500D01*
X715700Y-434367D01*
X716300Y-434500D01*
X716900Y-435033D01*
X717300Y-435967D01*
X717400Y-437033D01*
X717300Y-438100D01*
X716900Y-439033D01*
X716300Y-439567D01*
X715700Y-439700D01*
G01X723700D02*
Y-431700D01*
G01X730200Y-436100D02*
X733400D01*
X733100Y-435167D01*
X732600Y-434633D01*
X731900Y-434367D01*
X731200Y-434500D01*
X730600Y-434900D01*
X730200Y-435833D01*
X730000Y-436634D01*
Y-437433D01*
X730200Y-438233D01*
X730700Y-439033D01*
X731300Y-439567D01*
X732000Y-439700D01*
X732700Y-439433D01*
X733400Y-438634D01*
G01X747200Y-442367D02*
X746200Y-441033D01*
X745700Y-439700D01*
Y-434367D01*
X746200Y-433033D01*
X747200Y-431700D01*
G01X754000Y-439700D02*
Y-431700D01*
G01Y-435567D02*
X754500Y-434900D01*
X755000Y-434500D01*
X755800Y-434367D01*
X756400Y-434500D01*
X757100Y-435033D01*
X757400Y-435833D01*
Y-439700D01*
G01X763700D02*
X763100Y-439567D01*
X762500Y-439033D01*
X762100Y-438100D01*
X761900Y-437033D01*
X762100Y-435967D01*
X762500Y-435033D01*
X763100Y-434500D01*
X763700Y-434367D01*
X764300Y-434500D01*
X764900Y-435033D01*
X765300Y-435967D01*
X765400Y-437033D01*
X765300Y-438100D01*
X764900Y-439033D01*
X764300Y-439567D01*
X763700Y-439700D01*
G01X771700D02*
Y-431700D01*
G01X778200Y-436100D02*
X781400D01*
X781100Y-435167D01*
X780600Y-434633D01*
X779900Y-434367D01*
X779200Y-434500D01*
X778600Y-434900D01*
X778200Y-435833D01*
X778000Y-436634D01*
Y-437433D01*
X778200Y-438233D01*
X778700Y-439033D01*
X779300Y-439567D01*
X780000Y-439700D01*
X780700Y-439433D01*
X781400Y-438634D01*
G01X794200Y-438767D02*
X794700Y-439300D01*
X795400Y-439700D01*
X796000D01*
X796600Y-439433D01*
X797000Y-439033D01*
X797200Y-438500D01*
X797100Y-437700D01*
X796700Y-437300D01*
X794900Y-436500D01*
X794500Y-435567D01*
X794700Y-434900D01*
X795100Y-434500D01*
X795700Y-434367D01*
X796300Y-434500D01*
X796900Y-434900D01*
G01X803700Y-434367D02*
Y-439700D01*
G01Y-432233D02*
X803500Y-432100D01*
Y-431833D01*
X803700Y-431700D01*
X803900Y-431833D01*
Y-432100D01*
X803700Y-432233D01*
G01X810200Y-434367D02*
X813200D01*
X810200Y-439700D01*
X813200D01*
G01X818200Y-436100D02*
X821400D01*
X821100Y-435167D01*
X820600Y-434633D01*
X819900Y-434367D01*
X819200Y-434500D01*
X818600Y-434900D01*
X818200Y-435833D01*
X818000Y-436634D01*
Y-437433D01*
X818200Y-438233D01*
X818700Y-439033D01*
X819300Y-439567D01*
X820000Y-439700D01*
X820700Y-439433D01*
X821400Y-438634D01*
G01X837700Y-439700D02*
X833700Y-437033D01*
X837700Y-434367D01*
G01X842400Y-438233D02*
X845000D01*
G01Y-435833D02*
X842400D01*
G01X851700Y-439700D02*
Y-431700D01*
X850500Y-433300D01*
G01Y-439700D02*
X852900D01*
G01X857800Y-436367D02*
X858500Y-435433D01*
X859100Y-434900D01*
X859900Y-434633D01*
X860600Y-434900D01*
X861100Y-435433D01*
X861500Y-436233D01*
X861600Y-437167D01*
X861500Y-437967D01*
X861100Y-438767D01*
X860500Y-439433D01*
X859800Y-439700D01*
X859000Y-439433D01*
X858300Y-438634D01*
X857900Y-437433D01*
X857800Y-436100D01*
X858000Y-434367D01*
X858300Y-433433D01*
X858800Y-432500D01*
X859500Y-431833D01*
X860200Y-431700D01*
X860900Y-431967D01*
X861400Y-432633D01*
G01X872700Y-439700D02*
Y-434367D01*
G01Y-435833D02*
X873000Y-435167D01*
X873500Y-434633D01*
X874200Y-434367D01*
X874900Y-434633D01*
X875400Y-435167D01*
X875700Y-435833D01*
Y-439700D01*
G01Y-435833D02*
X876000Y-435167D01*
X876500Y-434633D01*
X877200Y-434367D01*
X877900Y-434633D01*
X878400Y-435167D01*
X878700Y-435967D01*
Y-439700D01*
G01X883700Y-434367D02*
Y-439700D01*
G01Y-432233D02*
X883500Y-432100D01*
Y-431833D01*
X883700Y-431700D01*
X883900Y-431833D01*
Y-432100D01*
X883700Y-432233D01*
G01X891700Y-439700D02*
Y-431700D01*
G01X900200Y-442367D02*
X901200Y-441033D01*
X901700Y-439700D01*
Y-434367D01*
X901200Y-433033D01*
X900200Y-431700D01*
G01X688200Y-419200D02*
Y-427200D01*
G01X686800Y-421867D02*
X689600D01*
G01X694500Y-427200D02*
Y-419200D01*
G01Y-423067D02*
X695000Y-422400D01*
X695500Y-422000D01*
X696300Y-421867D01*
X696900Y-422000D01*
X697600Y-422533D01*
X697900Y-423333D01*
Y-427200D01*
G01X702700Y-423600D02*
X705900D01*
X705600Y-422667D01*
X705100Y-422133D01*
X704400Y-421867D01*
X703700Y-422000D01*
X703100Y-422400D01*
X702700Y-423333D01*
X702500Y-424134D01*
Y-424933D01*
X702700Y-425733D01*
X703200Y-426533D01*
X703800Y-427067D01*
X704500Y-427200D01*
X705200Y-426933D01*
X705900Y-426134D01*
G01X718800Y-427200D02*
Y-421867D01*
G01Y-422933D02*
X719300Y-422400D01*
X719800Y-422000D01*
X720500Y-421867D01*
X721000Y-422000D01*
X721600Y-422400D01*
G01X726700Y-423600D02*
X729900D01*
X729600Y-422667D01*
X729100Y-422133D01*
X728400Y-421867D01*
X727700Y-422000D01*
X727100Y-422400D01*
X726700Y-423333D01*
X726500Y-424134D01*
Y-424933D01*
X726700Y-425733D01*
X727200Y-426533D01*
X727800Y-427067D01*
X728500Y-427200D01*
X729200Y-426933D01*
X729900Y-426134D01*
G01X736200Y-427200D02*
Y-419200D01*
G01X746000Y-427200D02*
Y-421867D01*
G01Y-422800D02*
X745600Y-422267D01*
X745000Y-422000D01*
X744300Y-421867D01*
X743600Y-422133D01*
X743000Y-422667D01*
X742600Y-423467D01*
X742400Y-424533D01*
X742600Y-425600D01*
X743000Y-426400D01*
X743600Y-426933D01*
X744300Y-427200D01*
X745000Y-427067D01*
X745600Y-426667D01*
X746000Y-426134D01*
G01X752200Y-419200D02*
Y-427200D01*
G01X750800Y-421867D02*
X753600D01*
G01X760200D02*
Y-427200D01*
G01Y-419733D02*
X760000Y-419600D01*
Y-419333D01*
X760200Y-419200D01*
X760400Y-419333D01*
Y-419600D01*
X760200Y-419733D01*
G01X766400Y-421867D02*
X768200Y-427200D01*
X770000Y-421867D01*
G01X774700Y-423600D02*
X777900D01*
X777600Y-422667D01*
X777100Y-422133D01*
X776400Y-421867D01*
X775700Y-422000D01*
X775100Y-422400D01*
X774700Y-423333D01*
X774500Y-424134D01*
Y-424933D01*
X774700Y-425733D01*
X775200Y-426533D01*
X775800Y-427067D01*
X776500Y-427200D01*
X777200Y-426933D01*
X777900Y-426134D01*
G01X792200Y-427200D02*
Y-419200D01*
G01X800200Y-427200D02*
X799600Y-427067D01*
X799000Y-426533D01*
X798600Y-425600D01*
X798400Y-424533D01*
X798600Y-423467D01*
X799000Y-422533D01*
X799600Y-422000D01*
X800200Y-421867D01*
X800800Y-422000D01*
X801400Y-422533D01*
X801800Y-423467D01*
X801900Y-424533D01*
X801800Y-425600D01*
X801400Y-426533D01*
X800800Y-427067D01*
X800200Y-427200D01*
G01X809800Y-422533D02*
X809100Y-422000D01*
X808500Y-421867D01*
X807700Y-422133D01*
X807100Y-422667D01*
X806700Y-423600D01*
X806600Y-424533D01*
X806700Y-425467D01*
X807100Y-426267D01*
X807700Y-426933D01*
X808500Y-427200D01*
X809200Y-426933D01*
X809800Y-426400D01*
G01X818000Y-427200D02*
Y-421867D01*
G01Y-422800D02*
X817600Y-422267D01*
X817000Y-422000D01*
X816300Y-421867D01*
X815600Y-422133D01*
X815000Y-422667D01*
X814600Y-423467D01*
X814400Y-424533D01*
X814600Y-425600D01*
X815000Y-426400D01*
X815600Y-426933D01*
X816300Y-427200D01*
X817000Y-427067D01*
X817600Y-426667D01*
X818000Y-426134D01*
G01X824200Y-419200D02*
Y-427200D01*
G01X822800Y-421867D02*
X825600D01*
G01X832200D02*
Y-427200D01*
G01Y-419733D02*
X832000Y-419600D01*
Y-419333D01*
X832200Y-419200D01*
X832400Y-419333D01*
Y-419600D01*
X832200Y-419733D01*
G01X840200Y-427200D02*
X839600Y-427067D01*
X839000Y-426533D01*
X838600Y-425600D01*
X838400Y-424533D01*
X838600Y-423467D01*
X839000Y-422533D01*
X839600Y-422000D01*
X840200Y-421867D01*
X840800Y-422000D01*
X841400Y-422533D01*
X841800Y-423467D01*
X841900Y-424533D01*
X841800Y-425600D01*
X841400Y-426533D01*
X840800Y-427067D01*
X840200Y-427200D01*
G01X846500D02*
Y-421867D01*
G01Y-423200D02*
X846900Y-422533D01*
X847500Y-422000D01*
X848300Y-421867D01*
X849000Y-422000D01*
X849600Y-422533D01*
X849900Y-423467D01*
Y-427200D01*
G01X864200D02*
X863600Y-427067D01*
X863000Y-426533D01*
X862600Y-425600D01*
X862400Y-424533D01*
X862600Y-423467D01*
X863000Y-422533D01*
X863600Y-422000D01*
X864200Y-421867D01*
X864800Y-422000D01*
X865400Y-422533D01*
X865800Y-423467D01*
X865900Y-424533D01*
X865800Y-425600D01*
X865400Y-426533D01*
X864800Y-427067D01*
X864200Y-427200D01*
G01X871600D02*
Y-420400D01*
X871800Y-419733D01*
X872200Y-419333D01*
X872800Y-419200D01*
X873400Y-419467D01*
X873700Y-420133D01*
G01X872500Y-422400D02*
X870500D01*
G01X886500Y-427200D02*
Y-419200D01*
G01Y-423067D02*
X887000Y-422400D01*
X887500Y-422000D01*
X888300Y-421867D01*
X888900Y-422000D01*
X889600Y-422533D01*
X889900Y-423333D01*
Y-427200D01*
G01X896200D02*
X895600Y-427067D01*
X895000Y-426533D01*
X894600Y-425600D01*
X894400Y-424533D01*
X894600Y-423467D01*
X895000Y-422533D01*
X895600Y-422000D01*
X896200Y-421867D01*
X896800Y-422000D01*
X897400Y-422533D01*
X897800Y-423467D01*
X897900Y-424533D01*
X897800Y-425600D01*
X897400Y-426533D01*
X896800Y-427067D01*
X896200Y-427200D01*
G01X904200D02*
Y-419200D01*
G01X910700Y-423600D02*
X913900D01*
X913600Y-422667D01*
X913100Y-422133D01*
X912400Y-421867D01*
X911700Y-422000D01*
X911100Y-422400D01*
X910700Y-423333D01*
X910500Y-424134D01*
Y-424933D01*
X910700Y-425733D01*
X911200Y-426533D01*
X911800Y-427067D01*
X912500Y-427200D01*
X913200Y-426933D01*
X913900Y-426134D01*
G01X928200Y-419200D02*
Y-427200D01*
G01X926800Y-421867D02*
X929600D01*
G01X936200Y-427200D02*
X935600Y-427067D01*
X935000Y-426533D01*
X934600Y-425600D01*
X934400Y-424533D01*
X934600Y-423467D01*
X935000Y-422533D01*
X935600Y-422000D01*
X936200Y-421867D01*
X936800Y-422000D01*
X937400Y-422533D01*
X937800Y-423467D01*
X937900Y-424533D01*
X937800Y-425600D01*
X937400Y-426533D01*
X936800Y-427067D01*
X936200Y-427200D01*
G01X950500D02*
Y-419200D01*
G01Y-423067D02*
X951000Y-422400D01*
X951500Y-422000D01*
X952300Y-421867D01*
X952900Y-422000D01*
X953600Y-422533D01*
X953900Y-423333D01*
Y-427200D01*
G01X960200D02*
X959600Y-427067D01*
X959000Y-426533D01*
X958600Y-425600D01*
X958400Y-424533D01*
X958600Y-423467D01*
X959000Y-422533D01*
X959600Y-422000D01*
X960200Y-421867D01*
X960800Y-422000D01*
X961400Y-422533D01*
X961800Y-423467D01*
X961900Y-424533D01*
X961800Y-425600D01*
X961400Y-426533D01*
X960800Y-427067D01*
X960200Y-427200D01*
G01X968200D02*
Y-419200D01*
G01X974700Y-423600D02*
X977900D01*
X977600Y-422667D01*
X977100Y-422133D01*
X976400Y-421867D01*
X975700Y-422000D01*
X975100Y-422400D01*
X974700Y-423333D01*
X974500Y-424134D01*
Y-424933D01*
X974700Y-425733D01*
X975200Y-426533D01*
X975800Y-427067D01*
X976500Y-427200D01*
X977200Y-426933D01*
X977900Y-426134D01*
G01X834500Y-404700D02*
X836900D01*
G01X835700D02*
Y-412700D01*
G01X834500D02*
X836900D01*
G01X843700Y-404700D02*
Y-412700D01*
G01X842300Y-407367D02*
X845100D01*
G01X850200Y-409100D02*
X853400D01*
X853100Y-408167D01*
X852600Y-407633D01*
X851900Y-407367D01*
X851200Y-407500D01*
X850600Y-407900D01*
X850200Y-408833D01*
X850000Y-409634D01*
Y-410433D01*
X850200Y-411233D01*
X850700Y-412033D01*
X851300Y-412567D01*
X852000Y-412700D01*
X852700Y-412433D01*
X853400Y-411634D01*
G01X856700Y-412700D02*
Y-407367D01*
G01Y-408833D02*
X857000Y-408167D01*
X857500Y-407633D01*
X858200Y-407367D01*
X858900Y-407633D01*
X859400Y-408167D01*
X859700Y-408833D01*
Y-412700D01*
G01Y-408833D02*
X860000Y-408167D01*
X860500Y-407633D01*
X861200Y-407367D01*
X861900Y-407633D01*
X862400Y-408167D01*
X862700Y-408967D01*
Y-412700D01*
G01X866200Y-411767D02*
X866700Y-412300D01*
X867400Y-412700D01*
X868000D01*
X868600Y-412433D01*
X869000Y-412033D01*
X869200Y-411500D01*
X869100Y-410700D01*
X868700Y-410300D01*
X866900Y-409500D01*
X866500Y-408567D01*
X866700Y-407900D01*
X867100Y-407500D01*
X867700Y-407367D01*
X868300Y-407500D01*
X868900Y-407900D01*
G01X1083100Y-524833D02*
X1085500D01*
G01X1084200Y-523100D02*
Y-526567D01*
G01X1092200Y-519500D02*
X1091400Y-519767D01*
X1090800Y-520433D01*
X1090400Y-521233D01*
X1090100Y-522300D01*
X1090000Y-523500D01*
X1090100Y-524700D01*
X1090400Y-525767D01*
X1090800Y-526567D01*
X1091400Y-527233D01*
X1092200Y-527500D01*
X1093000Y-527233D01*
X1093600Y-526567D01*
X1094000Y-525767D01*
X1094300Y-524700D01*
X1094400Y-523500D01*
X1094300Y-522300D01*
X1094000Y-521233D01*
X1093600Y-520433D01*
X1093000Y-519767D01*
X1092200Y-519500D01*
G01X1100200Y-527767D02*
X1100000Y-527633D01*
Y-527367D01*
X1100200Y-527233D01*
X1100400Y-527367D01*
Y-527633D01*
X1100200Y-527767D01*
G01X1108200Y-519500D02*
X1107400Y-519767D01*
X1106800Y-520433D01*
X1106400Y-521233D01*
X1106100Y-522300D01*
X1106000Y-523500D01*
X1106100Y-524700D01*
X1106400Y-525767D01*
X1106800Y-526567D01*
X1107400Y-527233D01*
X1108200Y-527500D01*
X1109000Y-527233D01*
X1109600Y-526567D01*
X1110000Y-525767D01*
X1110300Y-524700D01*
X1110400Y-523500D01*
X1110300Y-522300D01*
X1110000Y-521233D01*
X1109600Y-520433D01*
X1109000Y-519767D01*
X1108200Y-519500D01*
G01X1116000Y-527500D02*
X1116200Y-525767D01*
X1116500Y-524300D01*
X1116900Y-522967D01*
X1117400Y-521500D01*
X1118200Y-519500D01*
X1114200D01*
G01X1122000Y-526300D02*
X1122600Y-526967D01*
X1123300Y-527367D01*
X1124200Y-527500D01*
X1125100Y-527233D01*
X1125800Y-526700D01*
X1126300Y-525767D01*
X1126400Y-524700D01*
X1126200Y-523633D01*
X1125700Y-522967D01*
X1125000Y-522433D01*
X1124300Y-522300D01*
X1123600Y-522433D01*
X1122700Y-522967D01*
X1123000Y-519500D01*
X1125700D01*
G01X1130400Y-527767D02*
X1134000Y-519500D01*
G01X1138900Y-524833D02*
X1141500D01*
G01X1148200Y-519500D02*
X1147400Y-519767D01*
X1146800Y-520433D01*
X1146400Y-521233D01*
X1146100Y-522300D01*
X1146000Y-523500D01*
X1146100Y-524700D01*
X1146400Y-525767D01*
X1146800Y-526567D01*
X1147400Y-527233D01*
X1148200Y-527500D01*
X1149000Y-527233D01*
X1149600Y-526567D01*
X1150000Y-525767D01*
X1150300Y-524700D01*
X1150400Y-523500D01*
X1150300Y-522300D01*
X1150000Y-521233D01*
X1149600Y-520433D01*
X1149000Y-519767D01*
X1148200Y-519500D01*
G01X1153200Y-527500D02*
Y-522167D01*
G01Y-523633D02*
X1153500Y-522967D01*
X1154000Y-522433D01*
X1154700Y-522167D01*
X1155400Y-522433D01*
X1155900Y-522967D01*
X1156200Y-523633D01*
Y-527500D01*
G01Y-523633D02*
X1156500Y-522967D01*
X1157000Y-522433D01*
X1157700Y-522167D01*
X1158400Y-522433D01*
X1158900Y-522967D01*
X1159200Y-523767D01*
Y-527500D01*
G01X1161200D02*
Y-522167D01*
G01Y-523633D02*
X1161500Y-522967D01*
X1162000Y-522433D01*
X1162700Y-522167D01*
X1163400Y-522433D01*
X1163900Y-522967D01*
X1164200Y-523633D01*
Y-527500D01*
G01Y-523633D02*
X1164500Y-522967D01*
X1165000Y-522433D01*
X1165700Y-522167D01*
X1166400Y-522433D01*
X1166900Y-522967D01*
X1167200Y-523767D01*
Y-527500D01*
G01X1088700Y-577100D02*
Y-569100D01*
X1087500Y-570700D01*
G01Y-577100D02*
X1089900D01*
G01X1096700Y-577367D02*
X1096500Y-577233D01*
Y-576967D01*
X1096700Y-576833D01*
X1096900Y-576967D01*
Y-577233D01*
X1096700Y-577367D01*
G01X1104700Y-569100D02*
X1103900Y-569367D01*
X1103300Y-570033D01*
X1102900Y-570833D01*
X1102600Y-571900D01*
X1102500Y-573100D01*
X1102600Y-574300D01*
X1102900Y-575367D01*
X1103300Y-576167D01*
X1103900Y-576833D01*
X1104700Y-577100D01*
X1105500Y-576833D01*
X1106100Y-576167D01*
X1106500Y-575367D01*
X1106800Y-574300D01*
X1106900Y-573100D01*
X1106800Y-571900D01*
X1106500Y-570833D01*
X1106100Y-570033D01*
X1105500Y-569367D01*
X1104700Y-569100D01*
G01X1109700Y-577100D02*
Y-571767D01*
G01Y-573233D02*
X1110000Y-572567D01*
X1110500Y-572033D01*
X1111200Y-571767D01*
X1111900Y-572033D01*
X1112400Y-572567D01*
X1112700Y-573233D01*
Y-577100D01*
G01Y-573233D02*
X1113000Y-572567D01*
X1113500Y-572033D01*
X1114200Y-571767D01*
X1114900Y-572033D01*
X1115400Y-572567D01*
X1115700Y-573367D01*
Y-577100D01*
G01X1120700Y-571767D02*
Y-577100D01*
G01Y-569633D02*
X1120500Y-569500D01*
Y-569233D01*
X1120700Y-569100D01*
X1120900Y-569233D01*
Y-569500D01*
X1120700Y-569633D01*
G01X1128700Y-577100D02*
Y-569100D01*
G01X1141700Y-577100D02*
Y-571767D01*
G01Y-573233D02*
X1142000Y-572567D01*
X1142500Y-572033D01*
X1143200Y-571767D01*
X1143900Y-572033D01*
X1144400Y-572567D01*
X1144700Y-573233D01*
Y-577100D01*
G01Y-573233D02*
X1145000Y-572567D01*
X1145500Y-572033D01*
X1146200Y-571767D01*
X1146900Y-572033D01*
X1147400Y-572567D01*
X1147700Y-573367D01*
Y-577100D01*
G01X1154500D02*
Y-571767D01*
G01Y-572700D02*
X1154100Y-572167D01*
X1153500Y-571900D01*
X1152800Y-571767D01*
X1152100Y-572033D01*
X1151500Y-572567D01*
X1151100Y-573367D01*
X1150900Y-574433D01*
X1151100Y-575500D01*
X1151500Y-576300D01*
X1152100Y-576833D01*
X1152800Y-577100D01*
X1153500Y-576967D01*
X1154100Y-576567D01*
X1154500Y-576034D01*
G01X1159200Y-571767D02*
X1162200Y-577100D01*
G01Y-571767D02*
X1159200Y-577100D01*
G01X1094700Y-403700D02*
Y-411700D01*
G01X1092400Y-403700D02*
X1097000D01*
G01X1102700Y-411700D02*
X1102100Y-411567D01*
X1101500Y-411033D01*
X1101100Y-410100D01*
X1100900Y-409033D01*
X1101100Y-407967D01*
X1101500Y-407033D01*
X1102100Y-406500D01*
X1102700Y-406367D01*
X1103300Y-406500D01*
X1103900Y-407033D01*
X1104300Y-407967D01*
X1104400Y-409033D01*
X1104300Y-410100D01*
X1103900Y-411033D01*
X1103300Y-411567D01*
X1102700Y-411700D01*
G01X1110700D02*
Y-403700D01*
G01X1117200Y-408100D02*
X1120400D01*
X1120100Y-407167D01*
X1119600Y-406633D01*
X1118900Y-406367D01*
X1118200Y-406500D01*
X1117600Y-406900D01*
X1117200Y-407833D01*
X1117000Y-408634D01*
Y-409433D01*
X1117200Y-410233D01*
X1117700Y-411033D01*
X1118300Y-411567D01*
X1119000Y-411700D01*
X1119700Y-411433D01*
X1120400Y-410634D01*
G01X1125300Y-411700D02*
Y-406367D01*
G01Y-407433D02*
X1125800Y-406900D01*
X1126300Y-406500D01*
X1127000Y-406367D01*
X1127500Y-406500D01*
X1128100Y-406900D01*
G01X1136500Y-411700D02*
Y-406367D01*
G01Y-407300D02*
X1136100Y-406767D01*
X1135500Y-406500D01*
X1134800Y-406367D01*
X1134100Y-406633D01*
X1133500Y-407167D01*
X1133100Y-407967D01*
X1132900Y-409033D01*
X1133100Y-410100D01*
X1133500Y-410900D01*
X1134100Y-411433D01*
X1134800Y-411700D01*
X1135500Y-411567D01*
X1136100Y-411167D01*
X1136500Y-410634D01*
G01X1141000Y-411700D02*
Y-406367D01*
G01Y-407700D02*
X1141400Y-407033D01*
X1142000Y-406500D01*
X1142800Y-406367D01*
X1143500Y-406500D01*
X1144100Y-407033D01*
X1144400Y-407967D01*
Y-411700D01*
G01X1152300Y-407033D02*
X1151600Y-406500D01*
X1151000Y-406367D01*
X1150200Y-406633D01*
X1149600Y-407167D01*
X1149200Y-408100D01*
X1149100Y-409033D01*
X1149200Y-409967D01*
X1149600Y-410767D01*
X1150200Y-411433D01*
X1151000Y-411700D01*
X1151700Y-411433D01*
X1152300Y-410900D01*
G01X1157200Y-408100D02*
X1160400D01*
X1160100Y-407167D01*
X1159600Y-406633D01*
X1158900Y-406367D01*
X1158200Y-406500D01*
X1157600Y-406900D01*
X1157200Y-407833D01*
X1157000Y-408634D01*
Y-409433D01*
X1157200Y-410233D01*
X1157700Y-411033D01*
X1158300Y-411567D01*
X1159000Y-411700D01*
X1159700Y-411433D01*
X1160400Y-410634D01*
G01X1099600Y-549533D02*
X1102000D01*
G01X1100700Y-547800D02*
Y-551267D01*
G01X1106900Y-552467D02*
X1110500Y-544200D01*
G01X1115400Y-549533D02*
X1118000D01*
G01X1122500Y-551000D02*
X1123100Y-551667D01*
X1123800Y-552067D01*
X1124700Y-552200D01*
X1125600Y-551933D01*
X1126300Y-551400D01*
X1126800Y-550467D01*
X1126900Y-549400D01*
X1126700Y-548333D01*
X1126200Y-547667D01*
X1125500Y-547133D01*
X1124800Y-547000D01*
X1124100Y-547133D01*
X1123200Y-547667D01*
X1123500Y-544200D01*
X1126200D01*
G01X1129700Y-552200D02*
Y-546867D01*
G01Y-548333D02*
X1130000Y-547667D01*
X1130500Y-547133D01*
X1131200Y-546867D01*
X1131900Y-547133D01*
X1132400Y-547667D01*
X1132700Y-548333D01*
Y-552200D01*
G01Y-548333D02*
X1133000Y-547667D01*
X1133500Y-547133D01*
X1134200Y-546867D01*
X1134900Y-547133D01*
X1135400Y-547667D01*
X1135700Y-548467D01*
Y-552200D01*
G01X1140700Y-546867D02*
Y-552200D01*
G01Y-544733D02*
X1140500Y-544600D01*
Y-544333D01*
X1140700Y-544200D01*
X1140900Y-544333D01*
Y-544600D01*
X1140700Y-544733D01*
G01X1148700Y-552200D02*
Y-544200D01*
G01X1099600Y-562533D02*
X1102000D01*
G01X1100700Y-560800D02*
Y-564267D01*
G01X1106900Y-565467D02*
X1110500Y-557200D01*
G01X1115400Y-562533D02*
X1118000D01*
G01X1122500Y-564000D02*
X1123100Y-564667D01*
X1123800Y-565067D01*
X1124700Y-565200D01*
X1125600Y-564933D01*
X1126300Y-564400D01*
X1126800Y-563467D01*
X1126900Y-562400D01*
X1126700Y-561333D01*
X1126200Y-560667D01*
X1125500Y-560133D01*
X1124800Y-560000D01*
X1124100Y-560133D01*
X1123200Y-560667D01*
X1123500Y-557200D01*
X1126200D01*
G01X1129700Y-565200D02*
Y-559867D01*
G01Y-561333D02*
X1130000Y-560667D01*
X1130500Y-560133D01*
X1131200Y-559867D01*
X1131900Y-560133D01*
X1132400Y-560667D01*
X1132700Y-561333D01*
Y-565200D01*
G01Y-561333D02*
X1133000Y-560667D01*
X1133500Y-560133D01*
X1134200Y-559867D01*
X1134900Y-560133D01*
X1135400Y-560667D01*
X1135700Y-561467D01*
Y-565200D01*
G01X1140700Y-559867D02*
Y-565200D01*
G01Y-557733D02*
X1140500Y-557600D01*
Y-557333D01*
X1140700Y-557200D01*
X1140900Y-557333D01*
Y-557600D01*
X1140700Y-557733D01*
G01X1148700Y-565200D02*
Y-557200D01*
G01X1099600Y-537033D02*
X1102000D01*
G01X1100700Y-535300D02*
Y-538767D01*
G01X1106900Y-539967D02*
X1110500Y-531700D01*
G01X1115400Y-537033D02*
X1118000D01*
G01X1124700Y-531700D02*
X1123900Y-531967D01*
X1123300Y-532633D01*
X1122900Y-533433D01*
X1122600Y-534500D01*
X1122500Y-535700D01*
X1122600Y-536900D01*
X1122900Y-537967D01*
X1123300Y-538767D01*
X1123900Y-539433D01*
X1124700Y-539700D01*
X1125500Y-539433D01*
X1126100Y-538767D01*
X1126500Y-537967D01*
X1126800Y-536900D01*
X1126900Y-535700D01*
X1126800Y-534500D01*
X1126500Y-533433D01*
X1126100Y-532633D01*
X1125500Y-531967D01*
X1124700Y-531700D01*
G01X1132700Y-539967D02*
X1132500Y-539833D01*
Y-539567D01*
X1132700Y-539433D01*
X1132900Y-539567D01*
Y-539833D01*
X1132700Y-539967D01*
G01X1140700Y-531700D02*
X1139900Y-531967D01*
X1139300Y-532633D01*
X1138900Y-533433D01*
X1138600Y-534500D01*
X1138500Y-535700D01*
X1138600Y-536900D01*
X1138900Y-537967D01*
X1139300Y-538767D01*
X1139900Y-539433D01*
X1140700Y-539700D01*
X1141500Y-539433D01*
X1142100Y-538767D01*
X1142500Y-537967D01*
X1142800Y-536900D01*
X1142900Y-535700D01*
X1142800Y-534500D01*
X1142500Y-533433D01*
X1142100Y-532633D01*
X1141500Y-531967D01*
X1140700Y-531700D01*
G01X1146500Y-538500D02*
X1147100Y-539167D01*
X1147800Y-539567D01*
X1148700Y-539700D01*
X1149600Y-539433D01*
X1150300Y-538900D01*
X1150800Y-537967D01*
X1150900Y-536900D01*
X1150700Y-535833D01*
X1150200Y-535167D01*
X1149500Y-534633D01*
X1148800Y-534500D01*
X1148100Y-534633D01*
X1147200Y-535167D01*
X1147500Y-531700D01*
X1150200D01*
G01X1153700Y-539700D02*
Y-534367D01*
G01Y-535833D02*
X1154000Y-535167D01*
X1154500Y-534633D01*
X1155200Y-534367D01*
X1155900Y-534633D01*
X1156400Y-535167D01*
X1156700Y-535833D01*
Y-539700D01*
G01Y-535833D02*
X1157000Y-535167D01*
X1157500Y-534633D01*
X1158200Y-534367D01*
X1158900Y-534633D01*
X1159400Y-535167D01*
X1159700Y-535967D01*
Y-539700D01*
G01X1161700D02*
Y-534367D01*
G01Y-535833D02*
X1162000Y-535167D01*
X1162500Y-534633D01*
X1163200Y-534367D01*
X1163900Y-534633D01*
X1164400Y-535167D01*
X1164700Y-535833D01*
Y-539700D01*
G01Y-535833D02*
X1165000Y-535167D01*
X1165500Y-534633D01*
X1166200Y-534367D01*
X1166900Y-534633D01*
X1167400Y-535167D01*
X1167700Y-535967D01*
Y-539700D01*
G01X1099600Y-474533D02*
X1102000D01*
G01X1100700Y-472800D02*
Y-476267D01*
G01X1106900Y-477467D02*
X1110500Y-469200D01*
G01X1115400Y-474533D02*
X1118000D01*
G01X1122800Y-470533D02*
X1123400Y-469733D01*
X1124100Y-469333D01*
X1124900Y-469200D01*
X1125900Y-469467D01*
X1126600Y-470133D01*
X1126800Y-470933D01*
X1126700Y-471734D01*
X1126300Y-472400D01*
X1124300Y-473733D01*
X1123400Y-474667D01*
X1122800Y-476000D01*
X1122600Y-477200D01*
X1126800D01*
G01X1129700D02*
Y-471867D01*
G01Y-473333D02*
X1130000Y-472667D01*
X1130500Y-472133D01*
X1131200Y-471867D01*
X1131900Y-472133D01*
X1132400Y-472667D01*
X1132700Y-473333D01*
Y-477200D01*
G01Y-473333D02*
X1133000Y-472667D01*
X1133500Y-472133D01*
X1134200Y-471867D01*
X1134900Y-472133D01*
X1135400Y-472667D01*
X1135700Y-473467D01*
Y-477200D01*
G01X1140700Y-471867D02*
Y-477200D01*
G01Y-469733D02*
X1140500Y-469600D01*
Y-469333D01*
X1140700Y-469200D01*
X1140900Y-469333D01*
Y-469600D01*
X1140700Y-469733D01*
G01X1148700Y-477200D02*
Y-469200D01*
G01X1099600Y-512533D02*
X1102000D01*
G01X1100700Y-510800D02*
Y-514267D01*
G01X1106900Y-515467D02*
X1110500Y-507200D01*
G01X1115400Y-512533D02*
X1118000D01*
G01X1122800Y-508533D02*
X1123400Y-507733D01*
X1124100Y-507333D01*
X1124900Y-507200D01*
X1125900Y-507467D01*
X1126600Y-508133D01*
X1126800Y-508933D01*
X1126700Y-509734D01*
X1126300Y-510400D01*
X1124300Y-511733D01*
X1123400Y-512667D01*
X1122800Y-514000D01*
X1122600Y-515200D01*
X1126800D01*
G01X1129700D02*
Y-509867D01*
G01Y-511333D02*
X1130000Y-510667D01*
X1130500Y-510133D01*
X1131200Y-509867D01*
X1131900Y-510133D01*
X1132400Y-510667D01*
X1132700Y-511333D01*
Y-515200D01*
G01Y-511333D02*
X1133000Y-510667D01*
X1133500Y-510133D01*
X1134200Y-509867D01*
X1134900Y-510133D01*
X1135400Y-510667D01*
X1135700Y-511467D01*
Y-515200D01*
G01X1140700Y-509867D02*
Y-515200D01*
G01Y-507733D02*
X1140500Y-507600D01*
Y-507333D01*
X1140700Y-507200D01*
X1140900Y-507333D01*
Y-507600D01*
X1140700Y-507733D01*
G01X1148700Y-515200D02*
Y-507200D01*
G01X1099600Y-492033D02*
X1102000D01*
G01X1100700Y-490300D02*
Y-493767D01*
G01X1106900Y-494967D02*
X1110500Y-486700D01*
G01X1115400Y-492033D02*
X1118000D01*
G01X1122500Y-493100D02*
X1123100Y-494033D01*
X1123900Y-494567D01*
X1124800Y-494700D01*
X1125600Y-494567D01*
X1126400Y-493900D01*
X1126900Y-493100D01*
X1127000Y-492300D01*
X1126800Y-491367D01*
X1126100Y-490700D01*
X1125400Y-490433D01*
X1124500D01*
G01X1125400D02*
X1126000Y-490033D01*
X1126500Y-489367D01*
X1126700Y-488567D01*
X1126500Y-487767D01*
X1126000Y-487100D01*
X1125100Y-486700D01*
X1124200Y-486833D01*
X1123300Y-487367D01*
G01X1129700Y-494700D02*
Y-489367D01*
G01Y-490833D02*
X1130000Y-490167D01*
X1130500Y-489633D01*
X1131200Y-489367D01*
X1131900Y-489633D01*
X1132400Y-490167D01*
X1132700Y-490833D01*
Y-494700D01*
G01Y-490833D02*
X1133000Y-490167D01*
X1133500Y-489633D01*
X1134200Y-489367D01*
X1134900Y-489633D01*
X1135400Y-490167D01*
X1135700Y-490967D01*
Y-494700D01*
G01X1140700Y-489367D02*
Y-494700D01*
G01Y-487233D02*
X1140500Y-487100D01*
Y-486833D01*
X1140700Y-486700D01*
X1140900Y-486833D01*
Y-487100D01*
X1140700Y-487233D01*
G01X1148700Y-494700D02*
Y-486700D01*
G01X1099600Y-424533D02*
X1102000D01*
G01X1100700Y-422800D02*
Y-426267D01*
G01X1106900Y-427467D02*
X1110500Y-419200D01*
G01X1115400Y-424533D02*
X1118000D01*
G01X1122500Y-425600D02*
X1123100Y-426533D01*
X1123900Y-427067D01*
X1124800Y-427200D01*
X1125600Y-427067D01*
X1126400Y-426400D01*
X1126900Y-425600D01*
X1127000Y-424800D01*
X1126800Y-423867D01*
X1126100Y-423200D01*
X1125400Y-422933D01*
X1124500D01*
G01X1125400D02*
X1126000Y-422533D01*
X1126500Y-421867D01*
X1126700Y-421067D01*
X1126500Y-420267D01*
X1126000Y-419600D01*
X1125100Y-419200D01*
X1124200Y-419333D01*
X1123300Y-419867D01*
G01X1129700Y-427200D02*
Y-421867D01*
G01Y-423333D02*
X1130000Y-422667D01*
X1130500Y-422133D01*
X1131200Y-421867D01*
X1131900Y-422133D01*
X1132400Y-422667D01*
X1132700Y-423333D01*
Y-427200D01*
G01Y-423333D02*
X1133000Y-422667D01*
X1133500Y-422133D01*
X1134200Y-421867D01*
X1134900Y-422133D01*
X1135400Y-422667D01*
X1135700Y-423467D01*
Y-427200D01*
G01X1140700Y-421867D02*
Y-427200D01*
G01Y-419733D02*
X1140500Y-419600D01*
Y-419333D01*
X1140700Y-419200D01*
X1140900Y-419333D01*
Y-419600D01*
X1140700Y-419733D01*
G01X1148700Y-427200D02*
Y-419200D01*
G01X1099600Y-449033D02*
X1102000D01*
G01X1100700Y-447300D02*
Y-450767D01*
G01X1108700Y-451700D02*
Y-443700D01*
X1107500Y-445300D01*
G01Y-451700D02*
X1109900D01*
G01X1114900Y-451967D02*
X1118500Y-443700D01*
G01X1123400Y-449033D02*
X1126000D01*
G01X1130500Y-450100D02*
X1131100Y-451033D01*
X1131900Y-451567D01*
X1132800Y-451700D01*
X1133600Y-451567D01*
X1134400Y-450900D01*
X1134900Y-450100D01*
X1135000Y-449300D01*
X1134800Y-448367D01*
X1134100Y-447700D01*
X1133400Y-447433D01*
X1132500D01*
G01X1133400D02*
X1134000Y-447033D01*
X1134500Y-446367D01*
X1134700Y-445567D01*
X1134500Y-444767D01*
X1134000Y-444100D01*
X1133100Y-443700D01*
X1132200Y-443833D01*
X1131300Y-444367D01*
G01X1137700Y-451700D02*
Y-446367D01*
G01Y-447833D02*
X1138000Y-447167D01*
X1138500Y-446633D01*
X1139200Y-446367D01*
X1139900Y-446633D01*
X1140400Y-447167D01*
X1140700Y-447833D01*
Y-451700D01*
G01Y-447833D02*
X1141000Y-447167D01*
X1141500Y-446633D01*
X1142200Y-446367D01*
X1142900Y-446633D01*
X1143400Y-447167D01*
X1143700Y-447967D01*
Y-451700D01*
G01X1148700Y-446367D02*
Y-451700D01*
G01Y-444233D02*
X1148500Y-444100D01*
Y-443833D01*
X1148700Y-443700D01*
X1148900Y-443833D01*
Y-444100D01*
X1148700Y-444233D01*
G01X1156700Y-451700D02*
Y-443700D01*
G01X1099600Y-437033D02*
X1102000D01*
G01X1100700Y-435300D02*
Y-438767D01*
G01X1106800Y-433033D02*
X1107400Y-432233D01*
X1108100Y-431833D01*
X1108900Y-431700D01*
X1109900Y-431967D01*
X1110600Y-432633D01*
X1110800Y-433433D01*
X1110700Y-434234D01*
X1110300Y-434900D01*
X1108300Y-436233D01*
X1107400Y-437167D01*
X1106800Y-438500D01*
X1106600Y-439700D01*
X1110800D01*
G01X1114900Y-439967D02*
X1118500Y-431700D01*
G01X1123400Y-437033D02*
X1126000D01*
G01X1133900Y-439700D02*
Y-431700D01*
X1130200Y-437433D01*
X1135200D01*
G01X1137700Y-439700D02*
Y-434367D01*
G01Y-435833D02*
X1138000Y-435167D01*
X1138500Y-434633D01*
X1139200Y-434367D01*
X1139900Y-434633D01*
X1140400Y-435167D01*
X1140700Y-435833D01*
Y-439700D01*
G01Y-435833D02*
X1141000Y-435167D01*
X1141500Y-434633D01*
X1142200Y-434367D01*
X1142900Y-434633D01*
X1143400Y-435167D01*
X1143700Y-435967D01*
Y-439700D01*
G01X1148700Y-434367D02*
Y-439700D01*
G01Y-432233D02*
X1148500Y-432100D01*
Y-431833D01*
X1148700Y-431700D01*
X1148900Y-431833D01*
Y-432100D01*
X1148700Y-432233D01*
G01X1156700Y-439700D02*
Y-431700D01*
G01X-138200Y161700D02*
Y-707100D01*
X1402700D01*
Y161700D01*
X-138200D01*
G01Y-256700D02*
X1402700D01*
G01X60800Y-507400D02*
X85400D01*
X85600Y-507200D01*
X83200Y-504800D01*
G01X47300Y-469900D02*
Y-448700D01*
X47200Y-448600D01*
X42800Y-453000D01*
G01X47500Y-448800D02*
Y-448900D01*
X51600Y-453000D01*
G01X85300Y-448700D02*
X25500D01*
X25400Y-448600D01*
G01X48300Y-409200D02*
X48400D01*
X51500Y-406100D01*
G01X48300Y-408800D02*
X48700D01*
G01X48400Y-388900D02*
Y-408700D01*
X48100Y-409000D01*
X45100Y-406000D01*
G01X85200Y-409200D02*
X25300D01*
G01X43873Y-3903D02*
X43883Y-15903D01*
G01X43873Y-3903D02*
X67894Y-27883D01*
X67900Y-67200D01*
G01X43873Y-3903D02*
X55873Y-3893D01*
G01X112400Y-534200D02*
X112200D01*
X109600Y-536800D01*
G01X73300Y-534200D02*
X112200D01*
X112500Y-533900D01*
X109900Y-531300D01*
G01X112500Y-501800D02*
Y-549400D01*
G01X91700Y-507300D02*
Y-507500D01*
X94200Y-510000D01*
G01X107000Y-507400D02*
X91800D01*
X91700Y-507300D01*
X94300Y-504700D01*
G01X85400Y-507200D02*
Y-507500D01*
X83500Y-509400D01*
G01X91600Y-464600D02*
Y-513600D01*
X91500Y-513700D01*
G01X85600Y-464800D02*
Y-514000D01*
X85500Y-514100D01*
G01X85600Y-390100D02*
Y-318100D01*
G01X85900Y-335300D02*
Y-335400D01*
X87700Y-337200D01*
G01X99400Y-335300D02*
X86000D01*
X85800Y-335100D01*
X87900Y-333000D01*
G01X101320Y-22730D02*
X143320D01*
G01X101320D02*
X109320Y-30730D01*
G01X101320Y-22730D02*
X109320Y-14730D01*
G01X89780Y3840D02*
X113780Y27840D01*
X145780D01*
G01X89780Y3840D02*
Y15840D01*
G01Y3840D02*
X101780D01*
G01X137600Y-533800D02*
Y-533900D01*
X140800Y-537100D01*
G01X168800Y-533900D02*
X137700D01*
X137500Y-533700D01*
X140500Y-530700D01*
G01X137500Y-501300D02*
Y-549300D01*
G01Y-501800D02*
X231900D01*
X232500Y-502400D01*
G01X136500Y-355600D02*
X225800D01*
X226300Y-355100D01*
G01X164700Y-393200D02*
Y-320700D01*
X164800Y-320600D01*
G01X164700Y-335000D02*
Y-335100D01*
X162100Y-337700D01*
G01X143700Y-335100D02*
X164600D01*
X164800Y-334900D01*
X162000Y-332100D01*
X161900D01*
G01X190500Y-501300D02*
X190700D01*
X194300Y-497700D01*
G01X190400Y-501400D02*
X189900D01*
X186000Y-497500D01*
G01X190300Y-447500D02*
Y-501200D01*
X189700Y-501800D01*
G01X189200Y-355800D02*
X192400Y-359000D01*
G01X189100Y-355700D02*
X185700Y-359100D01*
G01X189200Y-356200D02*
Y-407400D01*
X189700Y-407900D01*
G01X505000Y161800D02*
Y-707100D01*
G01X528700Y-579700D02*
X1181700D01*
Y-399700D01*
X528700D01*
Y-579700D01*
G01X1181700Y-567200D02*
X528700D01*
G01Y-542200D02*
Y-554700D01*
X556700D01*
Y-542200D01*
G01X528700Y-517200D02*
Y-529700D01*
X556700D01*
Y-517200D01*
G01X528700Y-529700D02*
Y-542200D01*
X556700D01*
Y-529700D01*
G01Y-579700D02*
Y-554700D01*
G01Y-579700D02*
X670700D01*
Y-416700D01*
G01X528700Y-504700D02*
Y-517200D01*
X556700D01*
Y-504700D01*
G01X528700Y-492200D02*
Y-504700D01*
X556700D01*
Y-492200D01*
G01X528700Y-467200D02*
Y-479700D01*
X556700D01*
Y-467200D01*
G01X556200Y-439200D02*
X556700D01*
Y-495700D01*
G01X528700Y-442200D02*
Y-454700D01*
X556700D01*
Y-442200D01*
G01X528700Y-429700D02*
Y-442200D01*
X556700D01*
Y-429700D01*
G01X528700Y-417200D02*
Y-429700D01*
X556700D01*
Y-417200D01*
G01X1181700D02*
X528700D01*
G01X537700Y-399700D02*
X1181700D01*
Y-417200D01*
X528700D01*
Y-399700D01*
X537700D01*
G01X556700Y-417200D02*
Y-399700D01*
G01Y-429700D02*
X670700D01*
Y-417200D01*
G01X1181700Y-554700D02*
X670700D01*
G01X1181700Y-542200D02*
X670700D01*
G01Y-529700D02*
X1181700D01*
Y-517200D01*
G01D02*
X670700D01*
G01X1181700Y-504700D02*
X670700D01*
G01X1181700Y-479700D02*
X670700D01*
G01X1181700Y-442200D02*
X670700D01*
G01X1181700Y-454700D02*
X670700D01*
G01Y-417200D02*
Y-399700D01*
G01X1181700Y-429700D02*
X670700D01*
G01X1080200Y-579700D02*
Y-399700D01*
G01X1090200Y-554700D02*
X1181700D01*
Y-542200D01*
G01X1090200D02*
X1181700D01*
Y-529700D01*
G01X1090200Y-517200D02*
X1181700D01*
Y-504700D01*
G01X1090200D02*
X1181700D01*
Y-479700D01*
G01X1090200D02*
X1181700D01*
Y-442200D01*
G01X1090200Y-454700D02*
X1181700D01*
Y-442200D01*
G01X1090200D02*
X1181700D01*
Y-429700D01*
G01X1090200D02*
X1181700D01*
Y-417200D01*
G01X1162900Y-256700D02*
Y-256600D01*
M02*
